FILE_TYPE = MACRO_DRAWING;
SET COLOR_WIRE YELLOW;
SET COLOR_PROP ORANGE;
SET COLOR_DOT WHITE;
SET COLOR_ARC YELLOW;
SET COLOR_BODY GREEN;
SET COLOR_NOTE PURPLE;
SET PROP_DISPLAY VALUE;
SET PAGE_NUMBER P47;
FORCEADD GENOA_SP5..36
(-4500 3525);
FORCEPROP 1 LAST LOCATION U26
J 0
(-5145 6356);
DISPLAY 0.489362 (-5145 6356);
PAINT SKYBLUE (-5145 6356);
FORCEPROP 0 LAST $SEC 36
J 0
(-5125 6400);
DISPLAY 0.680851 (-5125 6400);
PAINT MONO (-5125 6400);
DISPLAY INVISIBLE (-5125 6400);
FORCEPROP 0 LAST CDS_SEC 36
J 0
(-5150 6350);
DISPLAY 1.021277 (-5150 6350);
DISPLAY INVISIBLE (-5150 6350);
FORCEPROP 0 LASTPIN (-5300 2900) $PN BC5
J 2
(-5310 2910);
DISPLAY 0.489362 (-5310 2910);
PAINT MONO (-5310 2910);
FORCEPROP 0 LASTPIN (-5300 2850) $PN BD6
J 2
(-5310 2860);
DISPLAY 0.489362 (-5310 2860);
PAINT MONO (-5310 2860);
FORCEPROP 0 LASTPIN (-5300 1750) $PN BF6
J 2
(-5310 1760);
DISPLAY 0.489362 (-5310 1760);
PAINT MONO (-5310 1760);
FORCEPROP 0 LASTPIN (-5300 1700) $PN BG5
J 2
(-5310 1710);
DISPLAY 0.489362 (-5310 1710);
PAINT MONO (-5310 1710);
FORCEPROP 0 LASTPIN (-5300 2050) $PN AT7
J 2
(-5310 2060);
DISPLAY 0.489362 (-5310 2060);
PAINT MONO (-5310 2060);
FORCEPROP 0 LASTPIN (-5300 1950) $PN AU7
J 2
(-5310 1960);
DISPLAY 0.489362 (-5310 1960);
PAINT MONO (-5310 1960);
FORCEPROP 0 LASTPIN (-5300 2750) $PN AU5
J 2
(-5310 2760);
DISPLAY 0.489362 (-5310 2760);
PAINT MONO (-5310 2760);
FORCEPROP 0 LASTPIN (-5300 2700) $PN AV7
J 2
(-5310 2710);
DISPLAY 0.489362 (-5310 2710);
PAINT MONO (-5310 2710);
FORCEPROP 0 LASTPIN (-5300 2600) $PN BN7
J 2
(-5310 2610);
DISPLAY 0.489362 (-5310 2610);
PAINT MONO (-5310 2610);
FORCEPROP 0 LASTPIN (-5300 1600) $PN AV6
J 2
(-5310 1610);
DISPLAY 0.489362 (-5310 1610);
PAINT MONO (-5310 1610);
FORCEPROP 0 LASTPIN (-5300 1550) $PN AW7
J 2
(-5310 1560);
DISPLAY 0.489362 (-5310 1560);
PAINT MONO (-5310 1560);
FORCEPROP 0 LASTPIN (-5300 1450) $PN BP7
J 2
(-5310 1460);
DISPLAY 0.489362 (-5310 1460);
PAINT MONO (-5310 1460);
FORCEPROP 0 LASTPIN (-5300 3750) $PN AW5
J 2
(-5310 3760);
DISPLAY 0.489362 (-5310 3760);
PAINT MONO (-5310 3760);
FORCEPROP 0 LASTPIN (-5300 3700) $PN AY6
J 2
(-5310 3710);
DISPLAY 0.489362 (-5310 3710);
PAINT MONO (-5310 3710);
FORCEPROP 0 LASTPIN (-5300 3650) $PN AY7
J 2
(-5310 3660);
DISPLAY 0.489362 (-5310 3660);
PAINT MONO (-5310 3660);
FORCEPROP 0 LASTPIN (-5300 3600) $PN BA7
J 2
(-5310 3610);
DISPLAY 0.489362 (-5310 3610);
PAINT MONO (-5310 3610);
FORCEPROP 0 LASTPIN (-5300 3550) $PN BA5
J 2
(-5310 3560);
DISPLAY 0.489362 (-5310 3560);
PAINT MONO (-5310 3560);
FORCEPROP 0 LASTPIN (-5300 3500) $PN BB6
J 2
(-5310 3510);
DISPLAY 0.489362 (-5310 3510);
PAINT MONO (-5310 3510);
FORCEPROP 0 LASTPIN (-5300 3450) $PN BB7
J 2
(-5310 3460);
DISPLAY 0.489362 (-5310 3460);
PAINT MONO (-5310 3460);
FORCEPROP 0 LASTPIN (-3700 2300) $PN AJ5
J 0
(-3690 2310);
DISPLAY 0.489362 (-3690 2310);
PAINT MONO (-3690 2310);
FORCEPROP 0 LASTPIN (-3700 2250) $PN AK7
J 0
(-3690 2260);
DISPLAY 0.489362 (-3690 2260);
PAINT MONO (-3690 2260);
FORCEPROP 0 LASTPIN (-3700 2200) $PN AK6
J 0
(-3690 2210);
DISPLAY 0.489362 (-3690 2210);
PAINT MONO (-3690 2210);
FORCEPROP 0 LASTPIN (-3700 2150) $PN AL7
J 0
(-3690 2160);
DISPLAY 0.489362 (-3690 2160);
PAINT MONO (-3690 2160);
FORCEPROP 0 LASTPIN (-3700 2100) $PN AN5
J 0
(-3690 2110);
DISPLAY 0.489362 (-3690 2110);
PAINT MONO (-3690 2110);
FORCEPROP 0 LASTPIN (-3700 2050) $PN AP7
J 0
(-3690 2060);
DISPLAY 0.489362 (-3690 2060);
PAINT MONO (-3690 2060);
FORCEPROP 0 LASTPIN (-3700 2000) $PN AP6
J 0
(-3690 2010);
DISPLAY 0.489362 (-3690 2010);
PAINT MONO (-3690 2010);
FORCEPROP 0 LASTPIN (-3700 1950) $PN AR7
J 0
(-3690 1960);
DISPLAY 0.489362 (-3690 1960);
PAINT MONO (-3690 1960);
FORCEPROP 0 LASTPIN (-3700 5900) $PN E5
J 0
(-3690 5910);
DISPLAY 0.489362 (-3690 5910);
PAINT MONO (-3690 5910);
FORCEPROP 0 LASTPIN (-3700 5850) $PN F7
J 0
(-3690 5860);
DISPLAY 0.489362 (-3690 5860);
PAINT MONO (-3690 5860);
FORCEPROP 0 LASTPIN (-3700 5800) $PN F6
J 0
(-3690 5810);
DISPLAY 0.489362 (-3690 5810);
PAINT MONO (-3690 5810);
FORCEPROP 0 LASTPIN (-3700 5750) $PN G7
J 0
(-3690 5760);
DISPLAY 0.489362 (-3690 5760);
PAINT MONO (-3690 5760);
FORCEPROP 0 LASTPIN (-3700 5700) $PN J5
J 0
(-3690 5710);
DISPLAY 0.489362 (-3690 5710);
PAINT MONO (-3690 5710);
FORCEPROP 0 LASTPIN (-3700 5650) $PN K7
J 0
(-3690 5660);
DISPLAY 0.489362 (-3690 5660);
PAINT MONO (-3690 5660);
FORCEPROP 0 LASTPIN (-3700 5600) $PN K6
J 0
(-3690 5610);
DISPLAY 0.489362 (-3690 5610);
PAINT MONO (-3690 5610);
FORCEPROP 0 LASTPIN (-3700 5550) $PN L7
J 0
(-3690 5560);
DISPLAY 0.489362 (-3690 5560);
PAINT MONO (-3690 5560);
FORCEPROP 0 LASTPIN (-3700 5450) $PN L5
J 0
(-3690 5460);
DISPLAY 0.489362 (-3690 5460);
PAINT MONO (-3690 5460);
FORCEPROP 0 LASTPIN (-3700 5400) $PN M7
J 0
(-3690 5410);
DISPLAY 0.489362 (-3690 5410);
PAINT MONO (-3690 5410);
FORCEPROP 0 LASTPIN (-3700 5350) $PN M6
J 0
(-3690 5360);
DISPLAY 0.489362 (-3690 5360);
PAINT MONO (-3690 5360);
FORCEPROP 0 LASTPIN (-3700 5300) $PN N7
J 0
(-3690 5310);
DISPLAY 0.489362 (-3690 5310);
PAINT MONO (-3690 5310);
FORCEPROP 0 LASTPIN (-3700 5250) $PN R5
J 0
(-3690 5260);
DISPLAY 0.489362 (-3690 5260);
PAINT MONO (-3690 5260);
FORCEPROP 0 LASTPIN (-3700 5200) $PN T7
J 0
(-3690 5210);
DISPLAY 0.489362 (-3690 5210);
PAINT MONO (-3690 5210);
FORCEPROP 0 LASTPIN (-3700 5150) $PN T6
J 0
(-3690 5160);
DISPLAY 0.489362 (-3690 5160);
PAINT MONO (-3690 5160);
FORCEPROP 0 LASTPIN (-3700 5100) $PN U7
J 0
(-3690 5110);
DISPLAY 0.489362 (-3690 5110);
PAINT MONO (-3690 5110);
FORCEPROP 0 LASTPIN (-3700 5000) $PN U5
J 0
(-3690 5010);
DISPLAY 0.489362 (-3690 5010);
PAINT MONO (-3690 5010);
FORCEPROP 0 LASTPIN (-3700 4950) $PN V7
J 0
(-3690 4960);
DISPLAY 0.489362 (-3690 4960);
PAINT MONO (-3690 4960);
FORCEPROP 0 LASTPIN (-3700 4900) $PN V6
J 0
(-3690 4910);
DISPLAY 0.489362 (-3690 4910);
PAINT MONO (-3690 4910);
FORCEPROP 0 LASTPIN (-3700 4850) $PN W7
J 0
(-3690 4860);
DISPLAY 0.489362 (-3690 4860);
PAINT MONO (-3690 4860);
FORCEPROP 0 LASTPIN (-3700 4800) $PN AA5
J 0
(-3690 4810);
DISPLAY 0.489362 (-3690 4810);
PAINT MONO (-3690 4810);
FORCEPROP 0 LASTPIN (-3700 4750) $PN AB7
J 0
(-3690 4760);
DISPLAY 0.489362 (-3690 4760);
PAINT MONO (-3690 4760);
FORCEPROP 0 LASTPIN (-3700 4700) $PN AB6
J 0
(-3690 4710);
DISPLAY 0.489362 (-3690 4710);
PAINT MONO (-3690 4710);
FORCEPROP 0 LASTPIN (-3700 4650) $PN AC7
J 0
(-3690 4660);
DISPLAY 0.489362 (-3690 4660);
PAINT MONO (-3690 4660);
FORCEPROP 0 LASTPIN (-3700 4550) $PN AC5
J 0
(-3690 4560);
DISPLAY 0.489362 (-3690 4560);
PAINT MONO (-3690 4560);
FORCEPROP 0 LASTPIN (-3700 4500) $PN AD7
J 0
(-3690 4510);
DISPLAY 0.489362 (-3690 4510);
PAINT MONO (-3690 4510);
FORCEPROP 0 LASTPIN (-3700 4450) $PN AD6
J 0
(-3690 4460);
DISPLAY 0.489362 (-3690 4460);
PAINT MONO (-3690 4460);
FORCEPROP 0 LASTPIN (-3700 4400) $PN AE7
J 0
(-3690 4410);
DISPLAY 0.489362 (-3690 4410);
PAINT MONO (-3690 4410);
FORCEPROP 0 LASTPIN (-3700 4350) $PN AG5
J 0
(-3690 4360);
DISPLAY 0.489362 (-3690 4360);
PAINT MONO (-3690 4360);
FORCEPROP 0 LASTPIN (-3700 4300) $PN AH7
J 0
(-3690 4310);
DISPLAY 0.489362 (-3690 4310);
PAINT MONO (-3690 4310);
FORCEPROP 0 LASTPIN (-3700 4250) $PN AH6
J 0
(-3690 4260);
DISPLAY 0.489362 (-3690 4260);
PAINT MONO (-3690 4260);
FORCEPROP 0 LASTPIN (-3700 4200) $PN AJ7
J 0
(-3690 4210);
DISPLAY 0.489362 (-3690 4210);
PAINT MONO (-3690 4210);
FORCEPROP 0 LASTPIN (-5300 5900) $PN G5
J 2
(-5310 5910);
DISPLAY 0.489362 (-5310 5910);
PAINT MONO (-5310 5910);
FORCEPROP 0 LASTPIN (-5300 5800) $PN N5
J 2
(-5310 5810);
DISPLAY 0.489362 (-5310 5810);
PAINT MONO (-5310 5810);
FORCEPROP 0 LASTPIN (-5300 5700) $PN W5
J 2
(-5310 5710);
DISPLAY 0.489362 (-5310 5710);
PAINT MONO (-5310 5710);
FORCEPROP 0 LASTPIN (-5300 5600) $PN AE5
J 2
(-5310 5610);
DISPLAY 0.489362 (-5310 5610);
PAINT MONO (-5310 5610);
FORCEPROP 0 LASTPIN (-5300 5500) $PN AL5
J 2
(-5310 5510);
DISPLAY 0.489362 (-5310 5510);
PAINT MONO (-5310 5510);
FORCEPROP 0 LASTPIN (-5300 5400) $PN J7
J 2
(-5310 5410);
DISPLAY 0.489362 (-5310 5410);
PAINT MONO (-5310 5410);
FORCEPROP 0 LASTPIN (-5300 5300) $PN R7
J 2
(-5310 5310);
DISPLAY 0.489362 (-5310 5310);
PAINT MONO (-5310 5310);
FORCEPROP 0 LASTPIN (-5300 5200) $PN AA7
J 2
(-5310 5210);
DISPLAY 0.489362 (-5310 5210);
PAINT MONO (-5310 5210);
FORCEPROP 0 LASTPIN (-5300 5100) $PN AG7
J 2
(-5310 5110);
DISPLAY 0.489362 (-5310 5110);
PAINT MONO (-5310 5110);
FORCEPROP 0 LASTPIN (-5300 5000) $PN AN7
J 2
(-5310 5010);
DISPLAY 0.489362 (-5310 5010);
PAINT MONO (-5310 5010);
FORCEPROP 0 LASTPIN (-5300 5850) $PN H6
J 2
(-5310 5860);
DISPLAY 0.489362 (-5310 5860);
PAINT MONO (-5310 5860);
FORCEPROP 0 LASTPIN (-5300 5750) $PN P6
J 2
(-5310 5760);
DISPLAY 0.489362 (-5310 5760);
PAINT MONO (-5310 5760);
FORCEPROP 0 LASTPIN (-5300 5650) $PN Y6
J 2
(-5310 5660);
DISPLAY 0.489362 (-5310 5660);
PAINT MONO (-5310 5660);
FORCEPROP 0 LASTPIN (-5300 5550) $PN AF6
J 2
(-5310 5560);
DISPLAY 0.489362 (-5310 5560);
PAINT MONO (-5310 5560);
FORCEPROP 0 LASTPIN (-5300 5450) $PN AM6
J 2
(-5310 5460);
DISPLAY 0.489362 (-5310 5460);
PAINT MONO (-5310 5460);
FORCEPROP 0 LASTPIN (-5300 5350) $PN H7
J 2
(-5310 5360);
DISPLAY 0.489362 (-5310 5360);
PAINT MONO (-5310 5360);
FORCEPROP 0 LASTPIN (-5300 5250) $PN P7
J 2
(-5310 5260);
DISPLAY 0.489362 (-5310 5260);
PAINT MONO (-5310 5260);
FORCEPROP 0 LASTPIN (-5300 5150) $PN Y7
J 2
(-5310 5160);
DISPLAY 0.489362 (-5310 5160);
PAINT MONO (-5310 5160);
FORCEPROP 0 LASTPIN (-5300 5050) $PN AF7
J 2
(-5310 5060);
DISPLAY 0.489362 (-5310 5060);
PAINT MONO (-5310 5060);
FORCEPROP 0 LASTPIN (-5300 4950) $PN AM7
J 2
(-5310 4960);
DISPLAY 0.489362 (-5310 4960);
PAINT MONO (-5310 4960);
FORCEPROP 0 LASTPIN (-5300 2500) $PN BC7
J 2
(-5310 2510);
DISPLAY 0.489362 (-5310 2510);
PAINT MONO (-5310 2510);
FORCEPROP 0 LASTPIN (-5300 2400) $PN BM7
J 2
(-5310 2410);
DISPLAY 0.489362 (-5310 2410);
PAINT MONO (-5310 2410);
FORCEPROP 0 LASTPIN (-5300 2350) $PN BN5
J 2
(-5310 2360);
DISPLAY 0.489362 (-5310 2360);
PAINT MONO (-5310 2360);
FORCEPROP 0 LASTPIN (-5300 2250) $PN BP6
J 2
(-5310 2260);
DISPLAY 0.489362 (-5310 2260);
PAINT MONO (-5310 2260);
FORCEPROP 0 LASTPIN (-5300 1350) $PN BL5
J 2
(-5310 1360);
DISPLAY 0.489362 (-5310 1360);
PAINT MONO (-5310 1360);
FORCEPROP 0 LASTPIN (-5300 1300) $PN BM6
J 2
(-5310 1310);
DISPLAY 0.489362 (-5310 1310);
PAINT MONO (-5310 1310);
FORCEPROP 0 LASTPIN (-5300 1200) $PN BR5
J 2
(-5310 1210);
DISPLAY 0.489362 (-5310 1210);
PAINT MONO (-5310 1210);
FORCEPROP 0 LASTPIN (-5300 3350) $PN BG7
J 2
(-5310 3360);
DISPLAY 0.489362 (-5310 3360);
PAINT MONO (-5310 3360);
FORCEPROP 0 LASTPIN (-5300 3300) $PN BH7
J 2
(-5310 3310);
DISPLAY 0.489362 (-5310 3310);
PAINT MONO (-5310 3310);
FORCEPROP 0 LASTPIN (-5300 3250) $PN BH6
J 2
(-5310 3260);
DISPLAY 0.489362 (-5310 3260);
PAINT MONO (-5310 3260);
FORCEPROP 0 LASTPIN (-5300 3200) $PN BJ5
J 2
(-5310 3210);
DISPLAY 0.489362 (-5310 3210);
PAINT MONO (-5310 3210);
FORCEPROP 0 LASTPIN (-5300 3150) $PN BJ7
J 2
(-5310 3160);
DISPLAY 0.489362 (-5310 3160);
PAINT MONO (-5310 3160);
FORCEPROP 0 LASTPIN (-5300 3100) $PN BK7
J 2
(-5310 3110);
DISPLAY 0.489362 (-5310 3110);
PAINT MONO (-5310 3110);
FORCEPROP 0 LASTPIN (-5300 3050) $PN BK6
J 2
(-5310 3060);
DISPLAY 0.489362 (-5310 3060);
PAINT MONO (-5310 3060);
FORCEPROP 0 LASTPIN (-3700 1850) $PN BY6
J 0
(-3690 1860);
DISPLAY 0.489362 (-3690 1860);
PAINT MONO (-3690 1860);
FORCEPROP 0 LASTPIN (-3700 1800) $PN CA7
J 0
(-3690 1810);
DISPLAY 0.489362 (-3690 1810);
PAINT MONO (-3690 1810);
FORCEPROP 0 LASTPIN (-3700 1750) $PN CA5
J 0
(-3690 1760);
DISPLAY 0.489362 (-3690 1760);
PAINT MONO (-3690 1760);
FORCEPROP 0 LASTPIN (-3700 1700) $PN CB7
J 0
(-3690 1710);
DISPLAY 0.489362 (-3690 1710);
PAINT MONO (-3690 1710);
FORCEPROP 0 LASTPIN (-3700 1650) $PN BT6
J 0
(-3690 1660);
DISPLAY 0.489362 (-3690 1660);
PAINT MONO (-3690 1660);
FORCEPROP 0 LASTPIN (-3700 1600) $PN BU7
J 0
(-3690 1610);
DISPLAY 0.489362 (-3690 1610);
PAINT MONO (-3690 1610);
FORCEPROP 0 LASTPIN (-3700 1550) $PN BU5
J 0
(-3690 1560);
DISPLAY 0.489362 (-3690 1560);
PAINT MONO (-3690 1560);
FORCEPROP 0 LASTPIN (-3700 1500) $PN BV7
J 0
(-3690 1510);
DISPLAY 0.489362 (-3690 1510);
PAINT MONO (-3690 1510);
FORCEPROP 0 LASTPIN (-3700 4100) $PN CB6
J 0
(-3690 4110);
DISPLAY 0.489362 (-3690 4110);
PAINT MONO (-3690 4110);
FORCEPROP 0 LASTPIN (-3700 4050) $PN CC7
J 0
(-3690 4060);
DISPLAY 0.489362 (-3690 4060);
PAINT MONO (-3690 4060);
FORCEPROP 0 LASTPIN (-3700 4000) $PN CC5
J 0
(-3690 4010);
DISPLAY 0.489362 (-3690 4010);
PAINT MONO (-3690 4010);
FORCEPROP 0 LASTPIN (-3700 3950) $PN CD7
J 0
(-3690 3960);
DISPLAY 0.489362 (-3690 3960);
PAINT MONO (-3690 3960);
FORCEPROP 0 LASTPIN (-3700 3900) $PN CF6
J 0
(-3690 3910);
DISPLAY 0.489362 (-3690 3910);
PAINT MONO (-3690 3910);
FORCEPROP 0 LASTPIN (-3700 3850) $PN CG7
J 0
(-3690 3860);
DISPLAY 0.489362 (-3690 3860);
PAINT MONO (-3690 3860);
FORCEPROP 0 LASTPIN (-3700 3800) $PN CG5
J 0
(-3690 3810);
DISPLAY 0.489362 (-3690 3810);
PAINT MONO (-3690 3810);
FORCEPROP 0 LASTPIN (-3700 3750) $PN CH7
J 0
(-3690 3760);
DISPLAY 0.489362 (-3690 3760);
PAINT MONO (-3690 3760);
FORCEPROP 0 LASTPIN (-3700 3650) $PN CH6
J 0
(-3690 3660);
DISPLAY 0.489362 (-3690 3660);
PAINT MONO (-3690 3660);
FORCEPROP 0 LASTPIN (-3700 3600) $PN CJ7
J 0
(-3690 3610);
DISPLAY 0.489362 (-3690 3610);
PAINT MONO (-3690 3610);
FORCEPROP 0 LASTPIN (-3700 3550) $PN CJ5
J 0
(-3690 3560);
DISPLAY 0.489362 (-3690 3560);
PAINT MONO (-3690 3560);
FORCEPROP 0 LASTPIN (-3700 3500) $PN CK7
J 0
(-3690 3510);
DISPLAY 0.489362 (-3690 3510);
PAINT MONO (-3690 3510);
FORCEPROP 0 LASTPIN (-3700 3450) $PN CM6
J 0
(-3690 3460);
DISPLAY 0.489362 (-3690 3460);
PAINT MONO (-3690 3460);
FORCEPROP 0 LASTPIN (-3700 3400) $PN CN7
J 0
(-3690 3410);
DISPLAY 0.489362 (-3690 3410);
PAINT MONO (-3690 3410);
FORCEPROP 0 LASTPIN (-3700 3350) $PN CN5
J 0
(-3690 3360);
DISPLAY 0.489362 (-3690 3360);
PAINT MONO (-3690 3360);
FORCEPROP 0 LASTPIN (-3700 3300) $PN CP7
J 0
(-3690 3310);
DISPLAY 0.489362 (-3690 3310);
PAINT MONO (-3690 3310);
FORCEPROP 0 LASTPIN (-3700 3200) $PN CP6
J 0
(-3690 3210);
DISPLAY 0.489362 (-3690 3210);
PAINT MONO (-3690 3210);
FORCEPROP 0 LASTPIN (-3700 3150) $PN CR7
J 0
(-3690 3160);
DISPLAY 0.489362 (-3690 3160);
PAINT MONO (-3690 3160);
FORCEPROP 0 LASTPIN (-3700 3100) $PN CR5
J 0
(-3690 3110);
DISPLAY 0.489362 (-3690 3110);
PAINT MONO (-3690 3110);
FORCEPROP 0 LASTPIN (-3700 3050) $PN CT7
J 0
(-3690 3060);
DISPLAY 0.489362 (-3690 3060);
PAINT MONO (-3690 3060);
FORCEPROP 0 LASTPIN (-3700 3000) $PN CV6
J 0
(-3690 3010);
DISPLAY 0.489362 (-3690 3010);
PAINT MONO (-3690 3010);
FORCEPROP 0 LASTPIN (-3700 2950) $PN CW7
J 0
(-3690 2960);
DISPLAY 0.489362 (-3690 2960);
PAINT MONO (-3690 2960);
FORCEPROP 0 LASTPIN (-3700 2900) $PN CW5
J 0
(-3690 2910);
DISPLAY 0.489362 (-3690 2910);
PAINT MONO (-3690 2910);
FORCEPROP 0 LASTPIN (-3700 2850) $PN CY7
J 0
(-3690 2860);
DISPLAY 0.489362 (-3690 2860);
PAINT MONO (-3690 2860);
FORCEPROP 0 LASTPIN (-3700 2750) $PN CY6
J 0
(-3690 2760);
DISPLAY 0.489362 (-3690 2760);
PAINT MONO (-3690 2760);
FORCEPROP 0 LASTPIN (-3700 2700) $PN DA7
J 0
(-3690 2710);
DISPLAY 0.489362 (-3690 2710);
PAINT MONO (-3690 2710);
FORCEPROP 0 LASTPIN (-3700 2650) $PN DA5
J 0
(-3690 2660);
DISPLAY 0.489362 (-3690 2660);
PAINT MONO (-3690 2660);
FORCEPROP 0 LASTPIN (-3700 2600) $PN DB7
J 0
(-3690 2610);
DISPLAY 0.489362 (-3690 2610);
PAINT MONO (-3690 2610);
FORCEPROP 0 LASTPIN (-3700 2550) $PN DD6
J 0
(-3690 2560);
DISPLAY 0.489362 (-3690 2560);
PAINT MONO (-3690 2560);
FORCEPROP 0 LASTPIN (-3700 2500) $PN DE7
J 0
(-3690 2510);
DISPLAY 0.489362 (-3690 2510);
PAINT MONO (-3690 2510);
FORCEPROP 0 LASTPIN (-3700 2450) $PN DE5
J 0
(-3690 2460);
DISPLAY 0.489362 (-3690 2460);
PAINT MONO (-3690 2460);
FORCEPROP 0 LASTPIN (-3700 2400) $PN DF7
J 0
(-3690 2410);
DISPLAY 0.489362 (-3690 2410);
PAINT MONO (-3690 2410);
FORCEPROP 0 LASTPIN (-5300 4850) $PN CD6
J 2
(-5310 4860);
DISPLAY 0.489362 (-5310 4860);
PAINT MONO (-5310 4860);
FORCEPROP 0 LASTPIN (-5300 4750) $PN CK6
J 2
(-5310 4760);
DISPLAY 0.489362 (-5310 4760);
PAINT MONO (-5310 4760);
FORCEPROP 0 LASTPIN (-5300 4650) $PN CT6
J 2
(-5310 4660);
DISPLAY 0.489362 (-5310 4660);
PAINT MONO (-5310 4660);
FORCEPROP 0 LASTPIN (-5300 4550) $PN DB6
J 2
(-5310 4560);
DISPLAY 0.489362 (-5310 4560);
PAINT MONO (-5310 4560);
FORCEPROP 0 LASTPIN (-5300 4450) $PN BY7
J 2
(-5310 4460);
DISPLAY 0.489362 (-5310 4460);
PAINT MONO (-5310 4460);
FORCEPROP 0 LASTPIN (-5300 4350) $PN CF7
J 2
(-5310 4360);
DISPLAY 0.489362 (-5310 4360);
PAINT MONO (-5310 4360);
FORCEPROP 0 LASTPIN (-5300 4250) $PN CM7
J 2
(-5310 4260);
DISPLAY 0.489362 (-5310 4260);
PAINT MONO (-5310 4260);
FORCEPROP 0 LASTPIN (-5300 4150) $PN CV7
J 2
(-5310 4160);
DISPLAY 0.489362 (-5310 4160);
PAINT MONO (-5310 4160);
FORCEPROP 0 LASTPIN (-5300 4050) $PN DD7
J 2
(-5310 4060);
DISPLAY 0.489362 (-5310 4060);
PAINT MONO (-5310 4060);
FORCEPROP 0 LASTPIN (-5300 3950) $PN BV6
J 2
(-5310 3960);
DISPLAY 0.489362 (-5310 3960);
PAINT MONO (-5310 3960);
FORCEPROP 0 LASTPIN (-5300 4800) $PN CE5
J 2
(-5310 4810);
DISPLAY 0.489362 (-5310 4810);
PAINT MONO (-5310 4810);
FORCEPROP 0 LASTPIN (-5300 4700) $PN CL5
J 2
(-5310 4710);
DISPLAY 0.489362 (-5310 4710);
PAINT MONO (-5310 4710);
FORCEPROP 0 LASTPIN (-5300 4600) $PN CU5
J 2
(-5310 4610);
DISPLAY 0.489362 (-5310 4610);
PAINT MONO (-5310 4610);
FORCEPROP 0 LASTPIN (-5300 4500) $PN DC5
J 2
(-5310 4510);
DISPLAY 0.489362 (-5310 4510);
PAINT MONO (-5310 4510);
FORCEPROP 0 LASTPIN (-5300 4400) $PN BW7
J 2
(-5310 4410);
DISPLAY 0.489362 (-5310 4410);
PAINT MONO (-5310 4410);
FORCEPROP 0 LASTPIN (-5300 4300) $PN CE7
J 2
(-5310 4310);
DISPLAY 0.489362 (-5310 4310);
PAINT MONO (-5310 4310);
FORCEPROP 0 LASTPIN (-5300 4200) $PN CL7
J 2
(-5310 4210);
DISPLAY 0.489362 (-5310 4210);
PAINT MONO (-5310 4210);
FORCEPROP 0 LASTPIN (-5300 4100) $PN CU7
J 2
(-5310 4110);
DISPLAY 0.489362 (-5310 4110);
PAINT MONO (-5310 4110);
FORCEPROP 0 LASTPIN (-5300 4000) $PN DC7
J 2
(-5310 4010);
DISPLAY 0.489362 (-5310 4010);
PAINT MONO (-5310 4010);
FORCEPROP 0 LASTPIN (-5300 3900) $PN BW5
J 2
(-5310 3910);
DISPLAY 0.489362 (-5310 3910);
PAINT MONO (-5310 3910);
FORCEPROP 0 LASTPIN (-5300 2150) $PN BL7
J 2
(-5310 2160);
DISPLAY 0.489362 (-5310 2160);
PAINT MONO (-5310 2160);
FORCEPROP 0 LASTPIN (-5300 1100) $PN BF7
J 2
(-5310 1110);
DISPLAY 0.489362 (-5310 1110);
PAINT MONO (-5310 1110);
FORCEPROP 2 LAST PART_TYPE SMLF
J 0
(-5150 6300);
DISPLAY 1.021277 (-5150 6300);
FORCEPROP 1 LAST MATERIAL IO
J 0
(-5145 6082);
DISPLAY 0.489362 (-5145 6082);
PAINT SKYBLUE (-5145 6082);
FORCEPROP 2 LAST VALUE SOCKET6096_13568-001
J 0
(-5150 6200);
DISPLAY 0.489362 (-5150 6200);
PAINT SKYBLUE (-5150 6200);
FORCEPROP 1 LAST PART_NUMBER DGA^6000030
J 0
(-5145 6209);
DISPLAY 0.489362 (-5145 6209);
PAINT SKYBLUE (-5145 6209);
FORCEPROP 2 LAST CDS_LIB pure_quanta
J 0
(-4500 3525);
DISPLAY INVISIBLE (-4500 3525);
FORCEPROP 1 LAST CDS_LMAN_SYM_OUTLINE -650,2525,650,-2525
J 0
(-4500 3525);
DISPLAY 0.468085 (-4500 3525);
PAINT GREEN (-4500 3525);
DISPLAY INVISIBLE (-4500 3525);
FORCEPROP 1 LAST NEEDS_NO_SIZE TRUE
J 0
(-4500 3525);
DISPLAY 0.723404 (-4500 3525);
PAINT GREEN (-4500 3525);
DISPLAY INVISIBLE (-4500 3525);
FORCEPROP 1 LAST PATH I159
J 0
(-4500 3525);
DISPLAY 0.723404 (-4500 3525);
PAINT GREEN (-4500 3525);
DISPLAY INVISIBLE (-4500 3525);
FORCEADD OFFPAGE..3
(-2500 5925);
FORCEPROP 2 LAST $XR0 107 
J 0
(-2286 5925);
DISPLAY 0.638298 (-2286 5925);
PAINT MONO (-2286 5925);
FORCEPROP 2 LAST PATH I160
J 0
(-2275 5975);
DISPLAY 1.021277 (-2275 5975);
DISPLAY INVISIBLE (-2275 5975);
FORCEPROP 1 LAST COMMENT_BODY TRUE
J 0
(-2550 5825);
DISPLAY 0.872340 (-2550 5825);
PAINT GREEN (-2550 5825);
DISPLAY INVISIBLE (-2550 5825);
FORCEPROP 1 LAST OFFPAGE TRUE
J 0
(-2175 5800);
DISPLAY 0.872340 (-2175 5800);
PAINT GREEN (-2175 5800);
DISPLAY INVISIBLE (-2175 5800);
FORCEPROP 2 LAST CDS_LIB mstr_standard
J 0
(-2500 5925);
DISPLAY 0.723404 (-2500 5925);
PAINT MONO (-2500 5925);
DISPLAY INVISIBLE (-2500 5925);
FORCEADD TAP..1
(-3225 5900);
FORCEPROP 3 LASTPIN (-3275 5900) SIG_NAME M_K_CPU1_SA_DQ<0>
J 0
(-3265 5910);
DISPLAY 0.659574 (-3265 5910);
PAINT MONO (-3265 5910);
DISPLAY INVISIBLE (-3265 5910);
FORCEPROP 1 LASTPIN (-3275 5900) BN 0
J 0
(-3287 5908);
DISPLAY 0.489362 (-3287 5908);
PAINT GREEN (-3287 5908);
FORCEPROP 2 LAST CDS_LIB mstr_standard
J 0
(-3225 5900);
DISPLAY 0.723404 (-3225 5900);
PAINT MONO (-3225 5900);
DISPLAY INVISIBLE (-3225 5900);
FORCEPROP 1 LAST BODY_TYPE PLUMBING
J 0
(-3225 5950);
DISPLAY 0.872340 (-3225 5950);
PAINT GREEN (-3225 5950);
DISPLAY INVISIBLE (-3225 5950);
FORCEPROP 1 LAST HDL_TAP TRUE
J 0
(-2900 5775);
DISPLAY 0.872340 (-2900 5775);
DISPLAY INVISIBLE (-2900 5775);
FORCEPROP 1 LAST PATH I161
J 0
(-3227 5900);
DISPLAY 0.872340 (-3227 5900);
PAINT GREEN (-3227 5900);
DISPLAY INVISIBLE (-3227 5900);
FORCEADD TAP..1
(-3225 5850);
FORCEPROP 3 LASTPIN (-3275 5850) SIG_NAME M_K_CPU1_SA_DQ<1>
J 0
(-3265 5860);
DISPLAY 0.659574 (-3265 5860);
PAINT MONO (-3265 5860);
DISPLAY INVISIBLE (-3265 5860);
FORCEPROP 1 LASTPIN (-3275 5850) BN 1
J 0
(-3287 5858);
DISPLAY 0.489362 (-3287 5858);
PAINT GREEN (-3287 5858);
FORCEPROP 2 LAST CDS_LIB mstr_standard
J 0
(-3225 5850);
DISPLAY 0.723404 (-3225 5850);
PAINT MONO (-3225 5850);
DISPLAY INVISIBLE (-3225 5850);
FORCEPROP 1 LAST BODY_TYPE PLUMBING
J 0
(-3225 5900);
DISPLAY 0.872340 (-3225 5900);
PAINT GREEN (-3225 5900);
DISPLAY INVISIBLE (-3225 5900);
FORCEPROP 1 LAST HDL_TAP TRUE
J 0
(-2900 5725);
DISPLAY 0.872340 (-2900 5725);
DISPLAY INVISIBLE (-2900 5725);
FORCEPROP 1 LAST PATH I162
J 0
(-3227 5850);
DISPLAY 0.872340 (-3227 5850);
PAINT GREEN (-3227 5850);
DISPLAY INVISIBLE (-3227 5850);
FORCEADD TAP..1
(-3225 5800);
FORCEPROP 3 LASTPIN (-3275 5800) SIG_NAME M_K_CPU1_SA_DQ<2>
J 0
(-3265 5810);
DISPLAY 0.659574 (-3265 5810);
PAINT MONO (-3265 5810);
DISPLAY INVISIBLE (-3265 5810);
FORCEPROP 1 LASTPIN (-3275 5800) BN 2
J 0
(-3287 5808);
DISPLAY 0.489362 (-3287 5808);
PAINT GREEN (-3287 5808);
FORCEPROP 2 LAST CDS_LIB mstr_standard
J 0
(-3225 5800);
DISPLAY 0.723404 (-3225 5800);
PAINT MONO (-3225 5800);
DISPLAY INVISIBLE (-3225 5800);
FORCEPROP 1 LAST BODY_TYPE PLUMBING
J 0
(-3225 5850);
DISPLAY 0.872340 (-3225 5850);
PAINT GREEN (-3225 5850);
DISPLAY INVISIBLE (-3225 5850);
FORCEPROP 1 LAST HDL_TAP TRUE
J 0
(-2900 5675);
DISPLAY 0.872340 (-2900 5675);
DISPLAY INVISIBLE (-2900 5675);
FORCEPROP 1 LAST PATH I163
J 0
(-3227 5800);
DISPLAY 0.872340 (-3227 5800);
PAINT GREEN (-3227 5800);
DISPLAY INVISIBLE (-3227 5800);
FORCEADD TAP..1
(-3225 5750);
FORCEPROP 3 LASTPIN (-3275 5750) SIG_NAME M_K_CPU1_SA_DQ<3>
J 0
(-3265 5760);
DISPLAY 0.659574 (-3265 5760);
PAINT MONO (-3265 5760);
DISPLAY INVISIBLE (-3265 5760);
FORCEPROP 1 LASTPIN (-3275 5750) BN 3
J 0
(-3287 5758);
DISPLAY 0.489362 (-3287 5758);
PAINT GREEN (-3287 5758);
FORCEPROP 2 LAST CDS_LIB mstr_standard
J 0
(-3225 5750);
DISPLAY 0.723404 (-3225 5750);
PAINT MONO (-3225 5750);
DISPLAY INVISIBLE (-3225 5750);
FORCEPROP 1 LAST BODY_TYPE PLUMBING
J 0
(-3225 5800);
DISPLAY 0.872340 (-3225 5800);
PAINT GREEN (-3225 5800);
DISPLAY INVISIBLE (-3225 5800);
FORCEPROP 1 LAST HDL_TAP TRUE
J 0
(-2900 5625);
DISPLAY 0.872340 (-2900 5625);
DISPLAY INVISIBLE (-2900 5625);
FORCEPROP 1 LAST PATH I164
J 0
(-3227 5750);
DISPLAY 0.872340 (-3227 5750);
PAINT GREEN (-3227 5750);
DISPLAY INVISIBLE (-3227 5750);
FORCEADD TAP..1
(-3225 5650);
FORCEPROP 3 LASTPIN (-3275 5650) SIG_NAME M_K_CPU1_SA_DQ<5>
J 0
(-3265 5660);
DISPLAY 0.659574 (-3265 5660);
PAINT MONO (-3265 5660);
DISPLAY INVISIBLE (-3265 5660);
FORCEPROP 1 LASTPIN (-3275 5650) BN 5
J 0
(-3287 5658);
DISPLAY 0.489362 (-3287 5658);
PAINT GREEN (-3287 5658);
FORCEPROP 2 LAST CDS_LIB mstr_standard
J 0
(-3225 5650);
DISPLAY 0.723404 (-3225 5650);
PAINT MONO (-3225 5650);
DISPLAY INVISIBLE (-3225 5650);
FORCEPROP 1 LAST BODY_TYPE PLUMBING
J 0
(-3225 5700);
DISPLAY 0.872340 (-3225 5700);
PAINT GREEN (-3225 5700);
DISPLAY INVISIBLE (-3225 5700);
FORCEPROP 1 LAST HDL_TAP TRUE
J 0
(-2900 5525);
DISPLAY 0.872340 (-2900 5525);
DISPLAY INVISIBLE (-2900 5525);
FORCEPROP 1 LAST PATH I165
J 0
(-3227 5650);
DISPLAY 0.872340 (-3227 5650);
PAINT GREEN (-3227 5650);
DISPLAY INVISIBLE (-3227 5650);
FORCEADD TAP..1
(-3225 5700);
FORCEPROP 3 LASTPIN (-3275 5700) SIG_NAME M_K_CPU1_SA_DQ<4>
J 0
(-3265 5710);
DISPLAY 0.659574 (-3265 5710);
PAINT MONO (-3265 5710);
DISPLAY INVISIBLE (-3265 5710);
FORCEPROP 1 LASTPIN (-3275 5700) BN 4
J 0
(-3287 5708);
DISPLAY 0.489362 (-3287 5708);
PAINT GREEN (-3287 5708);
FORCEPROP 2 LAST CDS_LIB mstr_standard
J 0
(-3225 5700);
DISPLAY 0.723404 (-3225 5700);
PAINT MONO (-3225 5700);
DISPLAY INVISIBLE (-3225 5700);
FORCEPROP 1 LAST BODY_TYPE PLUMBING
J 0
(-3225 5750);
DISPLAY 0.872340 (-3225 5750);
PAINT GREEN (-3225 5750);
DISPLAY INVISIBLE (-3225 5750);
FORCEPROP 1 LAST HDL_TAP TRUE
J 0
(-2900 5575);
DISPLAY 0.872340 (-2900 5575);
DISPLAY INVISIBLE (-2900 5575);
FORCEPROP 1 LAST PATH I166
J 0
(-3227 5700);
DISPLAY 0.872340 (-3227 5700);
PAINT GREEN (-3227 5700);
DISPLAY INVISIBLE (-3227 5700);
FORCEADD TAP..1
(-3225 5600);
FORCEPROP 3 LASTPIN (-3275 5600) SIG_NAME M_K_CPU1_SA_DQ<6>
J 0
(-3265 5610);
DISPLAY 0.659574 (-3265 5610);
PAINT MONO (-3265 5610);
DISPLAY INVISIBLE (-3265 5610);
FORCEPROP 1 LASTPIN (-3275 5600) BN 6
J 0
(-3287 5608);
DISPLAY 0.489362 (-3287 5608);
PAINT GREEN (-3287 5608);
FORCEPROP 2 LAST CDS_LIB mstr_standard
J 0
(-3225 5600);
DISPLAY 0.723404 (-3225 5600);
PAINT MONO (-3225 5600);
DISPLAY INVISIBLE (-3225 5600);
FORCEPROP 1 LAST BODY_TYPE PLUMBING
J 0
(-3225 5650);
DISPLAY 0.872340 (-3225 5650);
PAINT GREEN (-3225 5650);
DISPLAY INVISIBLE (-3225 5650);
FORCEPROP 1 LAST HDL_TAP TRUE
J 0
(-2900 5475);
DISPLAY 0.872340 (-2900 5475);
DISPLAY INVISIBLE (-2900 5475);
FORCEPROP 1 LAST PATH I167
J 0
(-3227 5600);
DISPLAY 0.872340 (-3227 5600);
PAINT GREEN (-3227 5600);
DISPLAY INVISIBLE (-3227 5600);
FORCEADD TAP..1
(-3225 5550);
FORCEPROP 3 LASTPIN (-3275 5550) SIG_NAME M_K_CPU1_SA_DQ<7>
J 0
(-3265 5560);
DISPLAY 0.659574 (-3265 5560);
PAINT MONO (-3265 5560);
DISPLAY INVISIBLE (-3265 5560);
FORCEPROP 1 LASTPIN (-3275 5550) BN 7
J 0
(-3287 5558);
DISPLAY 0.489362 (-3287 5558);
PAINT GREEN (-3287 5558);
FORCEPROP 2 LAST CDS_LIB mstr_standard
J 0
(-3225 5550);
DISPLAY 0.723404 (-3225 5550);
PAINT MONO (-3225 5550);
DISPLAY INVISIBLE (-3225 5550);
FORCEPROP 1 LAST BODY_TYPE PLUMBING
J 0
(-3225 5600);
DISPLAY 0.872340 (-3225 5600);
PAINT GREEN (-3225 5600);
DISPLAY INVISIBLE (-3225 5600);
FORCEPROP 1 LAST HDL_TAP TRUE
J 0
(-2900 5425);
DISPLAY 0.872340 (-2900 5425);
DISPLAY INVISIBLE (-2900 5425);
FORCEPROP 1 LAST PATH I168
J 0
(-3227 5550);
DISPLAY 0.872340 (-3227 5550);
PAINT GREEN (-3227 5550);
DISPLAY INVISIBLE (-3227 5550);
FORCEADD TAP..1
(-3225 5400);
FORCEPROP 3 LASTPIN (-3275 5400) SIG_NAME M_K_CPU1_SA_DQ<9>
J 0
(-3265 5410);
DISPLAY 0.659574 (-3265 5410);
PAINT MONO (-3265 5410);
DISPLAY INVISIBLE (-3265 5410);
FORCEPROP 1 LASTPIN (-3275 5400) BN 9
J 0
(-3287 5408);
DISPLAY 0.489362 (-3287 5408);
PAINT GREEN (-3287 5408);
FORCEPROP 2 LAST CDS_LIB mstr_standard
J 0
(-3225 5400);
DISPLAY 0.723404 (-3225 5400);
PAINT MONO (-3225 5400);
DISPLAY INVISIBLE (-3225 5400);
FORCEPROP 1 LAST BODY_TYPE PLUMBING
J 0
(-3225 5450);
DISPLAY 0.872340 (-3225 5450);
PAINT GREEN (-3225 5450);
DISPLAY INVISIBLE (-3225 5450);
FORCEPROP 1 LAST HDL_TAP TRUE
J 0
(-2900 5275);
DISPLAY 0.872340 (-2900 5275);
DISPLAY INVISIBLE (-2900 5275);
FORCEPROP 1 LAST PATH I169
J 0
(-3227 5400);
DISPLAY 0.872340 (-3227 5400);
PAINT GREEN (-3227 5400);
DISPLAY INVISIBLE (-3227 5400);
FORCEADD TAP..1
(-3225 5450);
FORCEPROP 3 LASTPIN (-3275 5450) SIG_NAME M_K_CPU1_SA_DQ<8>
J 0
(-3265 5460);
DISPLAY 0.659574 (-3265 5460);
PAINT MONO (-3265 5460);
DISPLAY INVISIBLE (-3265 5460);
FORCEPROP 1 LASTPIN (-3275 5450) BN 8
J 0
(-3287 5458);
DISPLAY 0.489362 (-3287 5458);
PAINT GREEN (-3287 5458);
FORCEPROP 2 LAST CDS_LIB mstr_standard
J 0
(-3225 5450);
DISPLAY 0.723404 (-3225 5450);
PAINT MONO (-3225 5450);
DISPLAY INVISIBLE (-3225 5450);
FORCEPROP 1 LAST BODY_TYPE PLUMBING
J 0
(-3225 5500);
DISPLAY 0.872340 (-3225 5500);
PAINT GREEN (-3225 5500);
DISPLAY INVISIBLE (-3225 5500);
FORCEPROP 1 LAST HDL_TAP TRUE
J 0
(-2900 5325);
DISPLAY 0.872340 (-2900 5325);
DISPLAY INVISIBLE (-2900 5325);
FORCEPROP 1 LAST PATH I170
J 0
(-3227 5450);
DISPLAY 0.872340 (-3227 5450);
PAINT GREEN (-3227 5450);
DISPLAY INVISIBLE (-3227 5450);
FORCEADD TAP..1
(-3225 5350);
FORCEPROP 3 LASTPIN (-3275 5350) SIG_NAME M_K_CPU1_SA_DQ<10>
J 0
(-3265 5360);
DISPLAY 0.659574 (-3265 5360);
PAINT MONO (-3265 5360);
DISPLAY INVISIBLE (-3265 5360);
FORCEPROP 1 LASTPIN (-3275 5350) BN 10
J 0
(-3287 5358);
DISPLAY 0.489362 (-3287 5358);
PAINT GREEN (-3287 5358);
FORCEPROP 2 LAST CDS_LIB mstr_standard
J 0
(-3225 5350);
DISPLAY 0.723404 (-3225 5350);
PAINT MONO (-3225 5350);
DISPLAY INVISIBLE (-3225 5350);
FORCEPROP 1 LAST BODY_TYPE PLUMBING
J 0
(-3225 5400);
DISPLAY 0.872340 (-3225 5400);
PAINT GREEN (-3225 5400);
DISPLAY INVISIBLE (-3225 5400);
FORCEPROP 1 LAST HDL_TAP TRUE
J 0
(-2900 5225);
DISPLAY 0.872340 (-2900 5225);
DISPLAY INVISIBLE (-2900 5225);
FORCEPROP 1 LAST PATH I171
J 0
(-3227 5350);
DISPLAY 0.872340 (-3227 5350);
PAINT GREEN (-3227 5350);
DISPLAY INVISIBLE (-3227 5350);
FORCEADD TAP..1
(-3225 5300);
FORCEPROP 3 LASTPIN (-3275 5300) SIG_NAME M_K_CPU1_SA_DQ<11>
J 0
(-3265 5310);
DISPLAY 0.659574 (-3265 5310);
PAINT MONO (-3265 5310);
DISPLAY INVISIBLE (-3265 5310);
FORCEPROP 1 LASTPIN (-3275 5300) BN 11
J 0
(-3287 5308);
DISPLAY 0.489362 (-3287 5308);
PAINT GREEN (-3287 5308);
FORCEPROP 2 LAST CDS_LIB mstr_standard
J 0
(-3225 5300);
DISPLAY 0.723404 (-3225 5300);
PAINT MONO (-3225 5300);
DISPLAY INVISIBLE (-3225 5300);
FORCEPROP 1 LAST BODY_TYPE PLUMBING
J 0
(-3225 5350);
DISPLAY 0.872340 (-3225 5350);
PAINT GREEN (-3225 5350);
DISPLAY INVISIBLE (-3225 5350);
FORCEPROP 1 LAST HDL_TAP TRUE
J 0
(-2900 5175);
DISPLAY 0.872340 (-2900 5175);
DISPLAY INVISIBLE (-2900 5175);
FORCEPROP 1 LAST PATH I172
J 0
(-3227 5300);
DISPLAY 0.872340 (-3227 5300);
PAINT GREEN (-3227 5300);
DISPLAY INVISIBLE (-3227 5300);
FORCEADD TAP..1
(-3225 5250);
FORCEPROP 3 LASTPIN (-3275 5250) SIG_NAME M_K_CPU1_SA_DQ<12>
J 0
(-3265 5260);
DISPLAY 0.659574 (-3265 5260);
PAINT MONO (-3265 5260);
DISPLAY INVISIBLE (-3265 5260);
FORCEPROP 1 LASTPIN (-3275 5250) BN 12
J 0
(-3287 5258);
DISPLAY 0.489362 (-3287 5258);
PAINT GREEN (-3287 5258);
FORCEPROP 2 LAST CDS_LIB mstr_standard
J 0
(-3225 5250);
DISPLAY 0.723404 (-3225 5250);
PAINT MONO (-3225 5250);
DISPLAY INVISIBLE (-3225 5250);
FORCEPROP 1 LAST BODY_TYPE PLUMBING
J 0
(-3225 5300);
DISPLAY 0.872340 (-3225 5300);
PAINT GREEN (-3225 5300);
DISPLAY INVISIBLE (-3225 5300);
FORCEPROP 1 LAST HDL_TAP TRUE
J 0
(-2900 5125);
DISPLAY 0.872340 (-2900 5125);
DISPLAY INVISIBLE (-2900 5125);
FORCEPROP 1 LAST PATH I173
J 0
(-3227 5250);
DISPLAY 0.872340 (-3227 5250);
PAINT GREEN (-3227 5250);
DISPLAY INVISIBLE (-3227 5250);
FORCEADD TAP..1
(-3225 5200);
FORCEPROP 3 LASTPIN (-3275 5200) SIG_NAME M_K_CPU1_SA_DQ<13>
J 0
(-3265 5210);
DISPLAY 0.659574 (-3265 5210);
PAINT MONO (-3265 5210);
DISPLAY INVISIBLE (-3265 5210);
FORCEPROP 1 LASTPIN (-3275 5200) BN 13
J 0
(-3287 5208);
DISPLAY 0.489362 (-3287 5208);
PAINT GREEN (-3287 5208);
FORCEPROP 2 LAST CDS_LIB mstr_standard
J 0
(-3225 5200);
DISPLAY 0.723404 (-3225 5200);
PAINT MONO (-3225 5200);
DISPLAY INVISIBLE (-3225 5200);
FORCEPROP 1 LAST BODY_TYPE PLUMBING
J 0
(-3225 5250);
DISPLAY 0.872340 (-3225 5250);
PAINT GREEN (-3225 5250);
DISPLAY INVISIBLE (-3225 5250);
FORCEPROP 1 LAST HDL_TAP TRUE
J 0
(-2900 5075);
DISPLAY 0.872340 (-2900 5075);
DISPLAY INVISIBLE (-2900 5075);
FORCEPROP 1 LAST PATH I174
J 0
(-3227 5200);
DISPLAY 0.872340 (-3227 5200);
PAINT GREEN (-3227 5200);
DISPLAY INVISIBLE (-3227 5200);
FORCEADD TAP..1
(-3225 5150);
FORCEPROP 3 LASTPIN (-3275 5150) SIG_NAME M_K_CPU1_SA_DQ<14>
J 0
(-3265 5160);
DISPLAY 0.659574 (-3265 5160);
PAINT MONO (-3265 5160);
DISPLAY INVISIBLE (-3265 5160);
FORCEPROP 1 LASTPIN (-3275 5150) BN 14
J 0
(-3287 5158);
DISPLAY 0.489362 (-3287 5158);
PAINT GREEN (-3287 5158);
FORCEPROP 2 LAST CDS_LIB mstr_standard
J 0
(-3225 5150);
DISPLAY 0.723404 (-3225 5150);
PAINT MONO (-3225 5150);
DISPLAY INVISIBLE (-3225 5150);
FORCEPROP 1 LAST BODY_TYPE PLUMBING
J 0
(-3225 5200);
DISPLAY 0.872340 (-3225 5200);
PAINT GREEN (-3225 5200);
DISPLAY INVISIBLE (-3225 5200);
FORCEPROP 1 LAST HDL_TAP TRUE
J 0
(-2900 5025);
DISPLAY 0.872340 (-2900 5025);
DISPLAY INVISIBLE (-2900 5025);
FORCEPROP 1 LAST PATH I175
J 0
(-3227 5150);
DISPLAY 0.872340 (-3227 5150);
PAINT GREEN (-3227 5150);
DISPLAY INVISIBLE (-3227 5150);
FORCEADD TAP..1
(-3225 4950);
FORCEPROP 3 LASTPIN (-3275 4950) SIG_NAME M_K_CPU1_SA_DQ<17>
J 0
(-3265 4960);
DISPLAY 0.659574 (-3265 4960);
PAINT MONO (-3265 4960);
DISPLAY INVISIBLE (-3265 4960);
FORCEPROP 1 LASTPIN (-3275 4950) BN 17
J 0
(-3287 4958);
DISPLAY 0.489362 (-3287 4958);
PAINT GREEN (-3287 4958);
FORCEPROP 2 LAST CDS_LIB mstr_standard
J 0
(-3225 4950);
DISPLAY 0.723404 (-3225 4950);
PAINT MONO (-3225 4950);
DISPLAY INVISIBLE (-3225 4950);
FORCEPROP 1 LAST BODY_TYPE PLUMBING
J 0
(-3225 5000);
DISPLAY 0.872340 (-3225 5000);
PAINT GREEN (-3225 5000);
DISPLAY INVISIBLE (-3225 5000);
FORCEPROP 1 LAST HDL_TAP TRUE
J 0
(-2900 4825);
DISPLAY 0.872340 (-2900 4825);
DISPLAY INVISIBLE (-2900 4825);
FORCEPROP 1 LAST PATH I176
J 0
(-3227 4950);
DISPLAY 0.872340 (-3227 4950);
PAINT GREEN (-3227 4950);
DISPLAY INVISIBLE (-3227 4950);
FORCEADD TAP..1
(-3225 5100);
FORCEPROP 3 LASTPIN (-3275 5100) SIG_NAME M_K_CPU1_SA_DQ<15>
J 0
(-3265 5110);
DISPLAY 0.659574 (-3265 5110);
PAINT MONO (-3265 5110);
DISPLAY INVISIBLE (-3265 5110);
FORCEPROP 1 LASTPIN (-3275 5100) BN 15
J 0
(-3287 5108);
DISPLAY 0.489362 (-3287 5108);
PAINT GREEN (-3287 5108);
FORCEPROP 2 LAST CDS_LIB mstr_standard
J 0
(-3225 5100);
DISPLAY 0.723404 (-3225 5100);
PAINT MONO (-3225 5100);
DISPLAY INVISIBLE (-3225 5100);
FORCEPROP 1 LAST BODY_TYPE PLUMBING
J 0
(-3225 5150);
DISPLAY 0.872340 (-3225 5150);
PAINT GREEN (-3225 5150);
DISPLAY INVISIBLE (-3225 5150);
FORCEPROP 1 LAST HDL_TAP TRUE
J 0
(-2900 4975);
DISPLAY 0.872340 (-2900 4975);
DISPLAY INVISIBLE (-2900 4975);
FORCEPROP 1 LAST PATH I177
J 0
(-3227 5100);
DISPLAY 0.872340 (-3227 5100);
PAINT GREEN (-3227 5100);
DISPLAY INVISIBLE (-3227 5100);
FORCEADD TAP..1
(-3225 5000);
FORCEPROP 3 LASTPIN (-3275 5000) SIG_NAME M_K_CPU1_SA_DQ<16>
J 0
(-3265 5010);
DISPLAY 0.659574 (-3265 5010);
PAINT MONO (-3265 5010);
DISPLAY INVISIBLE (-3265 5010);
FORCEPROP 1 LASTPIN (-3275 5000) BN 16
J 0
(-3287 5008);
DISPLAY 0.489362 (-3287 5008);
PAINT GREEN (-3287 5008);
FORCEPROP 2 LAST CDS_LIB mstr_standard
J 0
(-3225 5000);
DISPLAY 0.723404 (-3225 5000);
PAINT MONO (-3225 5000);
DISPLAY INVISIBLE (-3225 5000);
FORCEPROP 1 LAST BODY_TYPE PLUMBING
J 0
(-3225 5050);
DISPLAY 0.872340 (-3225 5050);
PAINT GREEN (-3225 5050);
DISPLAY INVISIBLE (-3225 5050);
FORCEPROP 1 LAST HDL_TAP TRUE
J 0
(-2900 4875);
DISPLAY 0.872340 (-2900 4875);
DISPLAY INVISIBLE (-2900 4875);
FORCEPROP 1 LAST PATH I178
J 0
(-3227 5000);
DISPLAY 0.872340 (-3227 5000);
PAINT GREEN (-3227 5000);
DISPLAY INVISIBLE (-3227 5000);
FORCEADD TAP..1
(-3225 4900);
FORCEPROP 3 LASTPIN (-3275 4900) SIG_NAME M_K_CPU1_SA_DQ<18>
J 0
(-3265 4910);
DISPLAY 0.659574 (-3265 4910);
PAINT MONO (-3265 4910);
DISPLAY INVISIBLE (-3265 4910);
FORCEPROP 1 LASTPIN (-3275 4900) BN 18
J 0
(-3287 4908);
DISPLAY 0.489362 (-3287 4908);
PAINT GREEN (-3287 4908);
FORCEPROP 2 LAST CDS_LIB mstr_standard
J 0
(-3225 4900);
DISPLAY 0.723404 (-3225 4900);
PAINT MONO (-3225 4900);
DISPLAY INVISIBLE (-3225 4900);
FORCEPROP 1 LAST BODY_TYPE PLUMBING
J 0
(-3225 4950);
DISPLAY 0.872340 (-3225 4950);
PAINT GREEN (-3225 4950);
DISPLAY INVISIBLE (-3225 4950);
FORCEPROP 1 LAST HDL_TAP TRUE
J 0
(-2900 4775);
DISPLAY 0.872340 (-2900 4775);
DISPLAY INVISIBLE (-2900 4775);
FORCEPROP 1 LAST PATH I179
J 0
(-3227 4900);
DISPLAY 0.872340 (-3227 4900);
PAINT GREEN (-3227 4900);
DISPLAY INVISIBLE (-3227 4900);
FORCEADD TAP..1
(-3225 4850);
FORCEPROP 3 LASTPIN (-3275 4850) SIG_NAME M_K_CPU1_SA_DQ<19>
J 0
(-3265 4860);
DISPLAY 0.659574 (-3265 4860);
PAINT MONO (-3265 4860);
DISPLAY INVISIBLE (-3265 4860);
FORCEPROP 1 LASTPIN (-3275 4850) BN 19
J 0
(-3287 4858);
DISPLAY 0.489362 (-3287 4858);
PAINT GREEN (-3287 4858);
FORCEPROP 2 LAST CDS_LIB mstr_standard
J 0
(-3225 4850);
DISPLAY 0.723404 (-3225 4850);
PAINT MONO (-3225 4850);
DISPLAY INVISIBLE (-3225 4850);
FORCEPROP 1 LAST BODY_TYPE PLUMBING
J 0
(-3225 4900);
DISPLAY 0.872340 (-3225 4900);
PAINT GREEN (-3225 4900);
DISPLAY INVISIBLE (-3225 4900);
FORCEPROP 1 LAST HDL_TAP TRUE
J 0
(-2900 4725);
DISPLAY 0.872340 (-2900 4725);
DISPLAY INVISIBLE (-2900 4725);
FORCEPROP 1 LAST PATH I180
J 0
(-3227 4850);
DISPLAY 0.872340 (-3227 4850);
PAINT GREEN (-3227 4850);
DISPLAY INVISIBLE (-3227 4850);
FORCEADD TAP..1
(-3225 4800);
FORCEPROP 3 LASTPIN (-3275 4800) SIG_NAME M_K_CPU1_SA_DQ<20>
J 0
(-3265 4810);
DISPLAY 0.659574 (-3265 4810);
PAINT MONO (-3265 4810);
DISPLAY INVISIBLE (-3265 4810);
FORCEPROP 1 LASTPIN (-3275 4800) BN 20
J 0
(-3287 4808);
DISPLAY 0.489362 (-3287 4808);
PAINT GREEN (-3287 4808);
FORCEPROP 2 LAST CDS_LIB mstr_standard
J 0
(-3225 4800);
DISPLAY 0.723404 (-3225 4800);
PAINT MONO (-3225 4800);
DISPLAY INVISIBLE (-3225 4800);
FORCEPROP 1 LAST BODY_TYPE PLUMBING
J 0
(-3225 4850);
DISPLAY 0.872340 (-3225 4850);
PAINT GREEN (-3225 4850);
DISPLAY INVISIBLE (-3225 4850);
FORCEPROP 1 LAST HDL_TAP TRUE
J 0
(-2900 4675);
DISPLAY 0.872340 (-2900 4675);
DISPLAY INVISIBLE (-2900 4675);
FORCEPROP 1 LAST PATH I181
J 0
(-3227 4800);
DISPLAY 0.872340 (-3227 4800);
PAINT GREEN (-3227 4800);
DISPLAY INVISIBLE (-3227 4800);
FORCEADD TAP..1
(-3225 4750);
FORCEPROP 3 LASTPIN (-3275 4750) SIG_NAME M_K_CPU1_SA_DQ<21>
J 0
(-3265 4760);
DISPLAY 0.659574 (-3265 4760);
PAINT MONO (-3265 4760);
DISPLAY INVISIBLE (-3265 4760);
FORCEPROP 1 LASTPIN (-3275 4750) BN 21
J 0
(-3287 4758);
DISPLAY 0.489362 (-3287 4758);
PAINT GREEN (-3287 4758);
FORCEPROP 2 LAST CDS_LIB mstr_standard
J 0
(-3225 4750);
DISPLAY 0.723404 (-3225 4750);
PAINT MONO (-3225 4750);
DISPLAY INVISIBLE (-3225 4750);
FORCEPROP 1 LAST BODY_TYPE PLUMBING
J 0
(-3225 4800);
DISPLAY 0.872340 (-3225 4800);
PAINT GREEN (-3225 4800);
DISPLAY INVISIBLE (-3225 4800);
FORCEPROP 1 LAST HDL_TAP TRUE
J 0
(-2900 4625);
DISPLAY 0.872340 (-2900 4625);
DISPLAY INVISIBLE (-2900 4625);
FORCEPROP 1 LAST PATH I182
J 0
(-3227 4750);
DISPLAY 0.872340 (-3227 4750);
PAINT GREEN (-3227 4750);
DISPLAY INVISIBLE (-3227 4750);
FORCEADD TAP..1
(-3225 4700);
FORCEPROP 3 LASTPIN (-3275 4700) SIG_NAME M_K_CPU1_SA_DQ<22>
J 0
(-3265 4710);
DISPLAY 0.659574 (-3265 4710);
PAINT MONO (-3265 4710);
DISPLAY INVISIBLE (-3265 4710);
FORCEPROP 1 LASTPIN (-3275 4700) BN 22
J 0
(-3287 4708);
DISPLAY 0.489362 (-3287 4708);
PAINT GREEN (-3287 4708);
FORCEPROP 2 LAST CDS_LIB mstr_standard
J 0
(-3225 4700);
DISPLAY 0.723404 (-3225 4700);
PAINT MONO (-3225 4700);
DISPLAY INVISIBLE (-3225 4700);
FORCEPROP 1 LAST BODY_TYPE PLUMBING
J 0
(-3225 4750);
DISPLAY 0.872340 (-3225 4750);
PAINT GREEN (-3225 4750);
DISPLAY INVISIBLE (-3225 4750);
FORCEPROP 1 LAST HDL_TAP TRUE
J 0
(-2900 4575);
DISPLAY 0.872340 (-2900 4575);
DISPLAY INVISIBLE (-2900 4575);
FORCEPROP 1 LAST PATH I183
J 0
(-3227 4700);
DISPLAY 0.872340 (-3227 4700);
PAINT GREEN (-3227 4700);
DISPLAY INVISIBLE (-3227 4700);
FORCEADD TAP..1
(-3225 4650);
FORCEPROP 3 LASTPIN (-3275 4650) SIG_NAME M_K_CPU1_SA_DQ<23>
J 0
(-3265 4660);
DISPLAY 0.659574 (-3265 4660);
PAINT MONO (-3265 4660);
DISPLAY INVISIBLE (-3265 4660);
FORCEPROP 1 LASTPIN (-3275 4650) BN 23
J 0
(-3287 4658);
DISPLAY 0.489362 (-3287 4658);
PAINT GREEN (-3287 4658);
FORCEPROP 2 LAST CDS_LIB mstr_standard
J 0
(-3225 4650);
DISPLAY 0.723404 (-3225 4650);
PAINT MONO (-3225 4650);
DISPLAY INVISIBLE (-3225 4650);
FORCEPROP 1 LAST BODY_TYPE PLUMBING
J 0
(-3225 4700);
DISPLAY 0.872340 (-3225 4700);
PAINT GREEN (-3225 4700);
DISPLAY INVISIBLE (-3225 4700);
FORCEPROP 1 LAST HDL_TAP TRUE
J 0
(-2900 4525);
DISPLAY 0.872340 (-2900 4525);
DISPLAY INVISIBLE (-2900 4525);
FORCEPROP 1 LAST PATH I184
J 0
(-3227 4650);
DISPLAY 0.872340 (-3227 4650);
PAINT GREEN (-3227 4650);
DISPLAY INVISIBLE (-3227 4650);
FORCEADD TAP..1
(-3225 4550);
FORCEPROP 3 LASTPIN (-3275 4550) SIG_NAME M_K_CPU1_SA_DQ<24>
J 0
(-3265 4560);
DISPLAY 0.659574 (-3265 4560);
PAINT MONO (-3265 4560);
DISPLAY INVISIBLE (-3265 4560);
FORCEPROP 1 LASTPIN (-3275 4550) BN 24
J 0
(-3287 4558);
DISPLAY 0.489362 (-3287 4558);
PAINT GREEN (-3287 4558);
FORCEPROP 2 LAST CDS_LIB mstr_standard
J 0
(-3225 4550);
DISPLAY 0.723404 (-3225 4550);
PAINT MONO (-3225 4550);
DISPLAY INVISIBLE (-3225 4550);
FORCEPROP 1 LAST BODY_TYPE PLUMBING
J 0
(-3225 4600);
DISPLAY 0.872340 (-3225 4600);
PAINT GREEN (-3225 4600);
DISPLAY INVISIBLE (-3225 4600);
FORCEPROP 1 LAST HDL_TAP TRUE
J 0
(-2900 4425);
DISPLAY 0.872340 (-2900 4425);
DISPLAY INVISIBLE (-2900 4425);
FORCEPROP 1 LAST PATH I185
J 0
(-3227 4550);
DISPLAY 0.872340 (-3227 4550);
PAINT GREEN (-3227 4550);
DISPLAY INVISIBLE (-3227 4550);
FORCEADD TAP..1
(-3225 4500);
FORCEPROP 3 LASTPIN (-3275 4500) SIG_NAME M_K_CPU1_SA_DQ<25>
J 0
(-3265 4510);
DISPLAY 0.659574 (-3265 4510);
PAINT MONO (-3265 4510);
DISPLAY INVISIBLE (-3265 4510);
FORCEPROP 1 LASTPIN (-3275 4500) BN 25
J 0
(-3287 4508);
DISPLAY 0.489362 (-3287 4508);
PAINT GREEN (-3287 4508);
FORCEPROP 2 LAST CDS_LIB mstr_standard
J 0
(-3225 4500);
DISPLAY 0.723404 (-3225 4500);
PAINT MONO (-3225 4500);
DISPLAY INVISIBLE (-3225 4500);
FORCEPROP 1 LAST BODY_TYPE PLUMBING
J 0
(-3225 4550);
DISPLAY 0.872340 (-3225 4550);
PAINT GREEN (-3225 4550);
DISPLAY INVISIBLE (-3225 4550);
FORCEPROP 1 LAST HDL_TAP TRUE
J 0
(-2900 4375);
DISPLAY 0.872340 (-2900 4375);
DISPLAY INVISIBLE (-2900 4375);
FORCEPROP 1 LAST PATH I186
J 0
(-3227 4500);
DISPLAY 0.872340 (-3227 4500);
PAINT GREEN (-3227 4500);
DISPLAY INVISIBLE (-3227 4500);
FORCEADD TAP..1
(-3225 4450);
FORCEPROP 3 LASTPIN (-3275 4450) SIG_NAME M_K_CPU1_SA_DQ<26>
J 0
(-3265 4460);
DISPLAY 0.659574 (-3265 4460);
PAINT MONO (-3265 4460);
DISPLAY INVISIBLE (-3265 4460);
FORCEPROP 1 LASTPIN (-3275 4450) BN 26
J 0
(-3287 4458);
DISPLAY 0.489362 (-3287 4458);
PAINT GREEN (-3287 4458);
FORCEPROP 2 LAST CDS_LIB mstr_standard
J 0
(-3225 4450);
DISPLAY 0.723404 (-3225 4450);
PAINT MONO (-3225 4450);
DISPLAY INVISIBLE (-3225 4450);
FORCEPROP 1 LAST BODY_TYPE PLUMBING
J 0
(-3225 4500);
DISPLAY 0.872340 (-3225 4500);
PAINT GREEN (-3225 4500);
DISPLAY INVISIBLE (-3225 4500);
FORCEPROP 1 LAST HDL_TAP TRUE
J 0
(-2900 4325);
DISPLAY 0.872340 (-2900 4325);
DISPLAY INVISIBLE (-2900 4325);
FORCEPROP 1 LAST PATH I187
J 0
(-3227 4450);
DISPLAY 0.872340 (-3227 4450);
PAINT GREEN (-3227 4450);
DISPLAY INVISIBLE (-3227 4450);
FORCEADD TAP..1
(-3225 4400);
FORCEPROP 3 LASTPIN (-3275 4400) SIG_NAME M_K_CPU1_SA_DQ<27>
J 0
(-3265 4410);
DISPLAY 0.659574 (-3265 4410);
PAINT MONO (-3265 4410);
DISPLAY INVISIBLE (-3265 4410);
FORCEPROP 1 LASTPIN (-3275 4400) BN 27
J 0
(-3287 4408);
DISPLAY 0.489362 (-3287 4408);
PAINT GREEN (-3287 4408);
FORCEPROP 2 LAST CDS_LIB mstr_standard
J 0
(-3225 4400);
DISPLAY 0.723404 (-3225 4400);
PAINT MONO (-3225 4400);
DISPLAY INVISIBLE (-3225 4400);
FORCEPROP 1 LAST BODY_TYPE PLUMBING
J 0
(-3225 4450);
DISPLAY 0.872340 (-3225 4450);
PAINT GREEN (-3225 4450);
DISPLAY INVISIBLE (-3225 4450);
FORCEPROP 1 LAST HDL_TAP TRUE
J 0
(-2900 4275);
DISPLAY 0.872340 (-2900 4275);
DISPLAY INVISIBLE (-2900 4275);
FORCEPROP 1 LAST PATH I188
J 0
(-3227 4400);
DISPLAY 0.872340 (-3227 4400);
PAINT GREEN (-3227 4400);
DISPLAY INVISIBLE (-3227 4400);
FORCEADD TAP..1
(-3225 4350);
FORCEPROP 3 LASTPIN (-3275 4350) SIG_NAME M_K_CPU1_SA_DQ<28>
J 0
(-3265 4360);
DISPLAY 0.659574 (-3265 4360);
PAINT MONO (-3265 4360);
DISPLAY INVISIBLE (-3265 4360);
FORCEPROP 1 LASTPIN (-3275 4350) BN 28
J 0
(-3287 4358);
DISPLAY 0.489362 (-3287 4358);
PAINT GREEN (-3287 4358);
FORCEPROP 2 LAST CDS_LIB mstr_standard
J 0
(-3225 4350);
DISPLAY 0.723404 (-3225 4350);
PAINT MONO (-3225 4350);
DISPLAY INVISIBLE (-3225 4350);
FORCEPROP 1 LAST BODY_TYPE PLUMBING
J 0
(-3225 4400);
DISPLAY 0.872340 (-3225 4400);
PAINT GREEN (-3225 4400);
DISPLAY INVISIBLE (-3225 4400);
FORCEPROP 1 LAST HDL_TAP TRUE
J 0
(-2900 4225);
DISPLAY 0.872340 (-2900 4225);
DISPLAY INVISIBLE (-2900 4225);
FORCEPROP 1 LAST PATH I189
J 0
(-3227 4350);
DISPLAY 0.872340 (-3227 4350);
PAINT GREEN (-3227 4350);
DISPLAY INVISIBLE (-3227 4350);
FORCEADD TAP..1
(-3225 4300);
FORCEPROP 3 LASTPIN (-3275 4300) SIG_NAME M_K_CPU1_SA_DQ<29>
J 0
(-3265 4310);
DISPLAY 0.659574 (-3265 4310);
PAINT MONO (-3265 4310);
DISPLAY INVISIBLE (-3265 4310);
FORCEPROP 1 LASTPIN (-3275 4300) BN 29
J 0
(-3287 4308);
DISPLAY 0.489362 (-3287 4308);
PAINT GREEN (-3287 4308);
FORCEPROP 2 LAST CDS_LIB mstr_standard
J 0
(-3225 4300);
DISPLAY 0.723404 (-3225 4300);
PAINT MONO (-3225 4300);
DISPLAY INVISIBLE (-3225 4300);
FORCEPROP 1 LAST BODY_TYPE PLUMBING
J 0
(-3225 4350);
DISPLAY 0.872340 (-3225 4350);
PAINT GREEN (-3225 4350);
DISPLAY INVISIBLE (-3225 4350);
FORCEPROP 1 LAST HDL_TAP TRUE
J 0
(-2900 4175);
DISPLAY 0.872340 (-2900 4175);
DISPLAY INVISIBLE (-2900 4175);
FORCEPROP 1 LAST PATH I190
J 0
(-3227 4300);
DISPLAY 0.872340 (-3227 4300);
PAINT GREEN (-3227 4300);
DISPLAY INVISIBLE (-3227 4300);
FORCEADD TAP..1
(-3225 4250);
FORCEPROP 3 LASTPIN (-3275 4250) SIG_NAME M_K_CPU1_SA_DQ<30>
J 0
(-3265 4260);
DISPLAY 0.659574 (-3265 4260);
PAINT MONO (-3265 4260);
DISPLAY INVISIBLE (-3265 4260);
FORCEPROP 1 LASTPIN (-3275 4250) BN 30
J 0
(-3287 4258);
DISPLAY 0.489362 (-3287 4258);
PAINT GREEN (-3287 4258);
FORCEPROP 2 LAST CDS_LIB mstr_standard
J 0
(-3225 4250);
DISPLAY 0.723404 (-3225 4250);
PAINT MONO (-3225 4250);
DISPLAY INVISIBLE (-3225 4250);
FORCEPROP 1 LAST BODY_TYPE PLUMBING
J 0
(-3225 4300);
DISPLAY 0.872340 (-3225 4300);
PAINT GREEN (-3225 4300);
DISPLAY INVISIBLE (-3225 4300);
FORCEPROP 1 LAST HDL_TAP TRUE
J 0
(-2900 4125);
DISPLAY 0.872340 (-2900 4125);
DISPLAY INVISIBLE (-2900 4125);
FORCEPROP 1 LAST PATH I191
J 0
(-3227 4250);
DISPLAY 0.872340 (-3227 4250);
PAINT GREEN (-3227 4250);
DISPLAY INVISIBLE (-3227 4250);
FORCEADD TAP..1
(-3225 4200);
FORCEPROP 3 LASTPIN (-3275 4200) SIG_NAME M_K_CPU1_SA_DQ<31>
J 0
(-3265 4210);
DISPLAY 0.659574 (-3265 4210);
PAINT MONO (-3265 4210);
DISPLAY INVISIBLE (-3265 4210);
FORCEPROP 1 LASTPIN (-3275 4200) BN 31
J 0
(-3287 4208);
DISPLAY 0.489362 (-3287 4208);
PAINT GREEN (-3287 4208);
FORCEPROP 2 LAST CDS_LIB mstr_standard
J 0
(-3225 4200);
DISPLAY 0.723404 (-3225 4200);
PAINT MONO (-3225 4200);
DISPLAY INVISIBLE (-3225 4200);
FORCEPROP 1 LAST BODY_TYPE PLUMBING
J 0
(-3225 4250);
DISPLAY 0.872340 (-3225 4250);
PAINT GREEN (-3225 4250);
DISPLAY INVISIBLE (-3225 4250);
FORCEPROP 1 LAST HDL_TAP TRUE
J 0
(-2900 4075);
DISPLAY 0.872340 (-2900 4075);
DISPLAY INVISIBLE (-2900 4075);
FORCEPROP 1 LAST PATH I192
J 0
(-3227 4200);
DISPLAY 0.872340 (-3227 4200);
PAINT GREEN (-3227 4200);
DISPLAY INVISIBLE (-3227 4200);
FORCEADD TAP..1
(-3225 4100);
FORCEPROP 3 LASTPIN (-3275 4100) SIG_NAME M_K_CPU1_SB_DQ<0>
J 0
(-3265 4110);
DISPLAY 0.659574 (-3265 4110);
PAINT MONO (-3265 4110);
DISPLAY INVISIBLE (-3265 4110);
FORCEPROP 1 LASTPIN (-3275 4100) BN 0
J 0
(-3287 4108);
DISPLAY 0.489362 (-3287 4108);
PAINT GREEN (-3287 4108);
FORCEPROP 2 LAST CDS_LIB mstr_standard
J 0
(-3225 4100);
DISPLAY 0.723404 (-3225 4100);
PAINT MONO (-3225 4100);
DISPLAY INVISIBLE (-3225 4100);
FORCEPROP 1 LAST BODY_TYPE PLUMBING
J 0
(-3225 4150);
DISPLAY 0.872340 (-3225 4150);
PAINT GREEN (-3225 4150);
DISPLAY INVISIBLE (-3225 4150);
FORCEPROP 1 LAST HDL_TAP TRUE
J 0
(-2900 3975);
DISPLAY 0.872340 (-2900 3975);
DISPLAY INVISIBLE (-2900 3975);
FORCEPROP 1 LAST PATH I193
J 0
(-3227 4100);
DISPLAY 0.872340 (-3227 4100);
PAINT GREEN (-3227 4100);
DISPLAY INVISIBLE (-3227 4100);
FORCEADD OFFPAGE..3
(-2500 4125);
FORCEPROP 2 LAST $XR0 107 
J 0
(-2286 4125);
DISPLAY 0.638298 (-2286 4125);
PAINT MONO (-2286 4125);
FORCEPROP 2 LAST PATH I194
J 0
(-2275 4175);
DISPLAY 1.021277 (-2275 4175);
DISPLAY INVISIBLE (-2275 4175);
FORCEPROP 1 LAST COMMENT_BODY TRUE
J 0
(-2550 4025);
DISPLAY 0.872340 (-2550 4025);
PAINT GREEN (-2550 4025);
DISPLAY INVISIBLE (-2550 4025);
FORCEPROP 1 LAST OFFPAGE TRUE
J 0
(-2175 4000);
DISPLAY 0.872340 (-2175 4000);
PAINT GREEN (-2175 4000);
DISPLAY INVISIBLE (-2175 4000);
FORCEPROP 2 LAST CDS_LIB mstr_standard
J 0
(-2500 4125);
DISPLAY 0.723404 (-2500 4125);
PAINT MONO (-2500 4125);
DISPLAY INVISIBLE (-2500 4125);
FORCEADD OFFPAGE..6
R 2
(-2625 2350);
FORCEPROP 2 LAST $XR0 107 
J 0
(-2411 2350);
DISPLAY 0.638298 (-2411 2350);
PAINT MONO (-2411 2350);
FORCEPROP 2 LAST PATH I195
J 0
(-2400 2400);
DISPLAY 1.021277 (-2400 2400);
DISPLAY INVISIBLE (-2400 2400);
FORCEPROP 1 LAST COMMENT_BODY TRUE
J 2
(-2725 2275);
DISPLAY 0.872340 (-2725 2275);
PAINT GREEN (-2725 2275);
DISPLAY INVISIBLE (-2725 2275);
FORCEPROP 1 LAST OFFPAGE TRUE
J 2
(-2950 2225);
DISPLAY 0.872340 (-2950 2225);
PAINT GREEN (-2950 2225);
DISPLAY INVISIBLE (-2950 2225);
FORCEPROP 2 LAST CDS_LIB mstr_standard
J 2
(-2625 2350);
DISPLAY 0.723404 (-2625 2350);
PAINT MONO (-2625 2350);
DISPLAY INVISIBLE (-2625 2350);
FORCEADD TAP..1
(-3225 4050);
FORCEPROP 3 LASTPIN (-3275 4050) SIG_NAME M_K_CPU1_SB_DQ<1>
J 0
(-3265 4060);
DISPLAY 0.659574 (-3265 4060);
PAINT MONO (-3265 4060);
DISPLAY INVISIBLE (-3265 4060);
FORCEPROP 1 LASTPIN (-3275 4050) BN 1
J 0
(-3287 4058);
DISPLAY 0.489362 (-3287 4058);
PAINT GREEN (-3287 4058);
FORCEPROP 2 LAST CDS_LIB mstr_standard
J 0
(-3225 4050);
DISPLAY 0.723404 (-3225 4050);
PAINT MONO (-3225 4050);
DISPLAY INVISIBLE (-3225 4050);
FORCEPROP 1 LAST BODY_TYPE PLUMBING
J 0
(-3225 4100);
DISPLAY 0.872340 (-3225 4100);
PAINT GREEN (-3225 4100);
DISPLAY INVISIBLE (-3225 4100);
FORCEPROP 1 LAST HDL_TAP TRUE
J 0
(-2900 3925);
DISPLAY 0.872340 (-2900 3925);
DISPLAY INVISIBLE (-2900 3925);
FORCEPROP 1 LAST PATH I196
J 0
(-3227 4050);
DISPLAY 0.872340 (-3227 4050);
PAINT GREEN (-3227 4050);
DISPLAY INVISIBLE (-3227 4050);
FORCEADD TAP..1
(-3225 4000);
FORCEPROP 3 LASTPIN (-3275 4000) SIG_NAME M_K_CPU1_SB_DQ<2>
J 0
(-3265 4010);
DISPLAY 0.659574 (-3265 4010);
PAINT MONO (-3265 4010);
DISPLAY INVISIBLE (-3265 4010);
FORCEPROP 1 LASTPIN (-3275 4000) BN 2
J 0
(-3287 4008);
DISPLAY 0.489362 (-3287 4008);
PAINT GREEN (-3287 4008);
FORCEPROP 2 LAST CDS_LIB mstr_standard
J 0
(-3225 4000);
DISPLAY 0.723404 (-3225 4000);
PAINT MONO (-3225 4000);
DISPLAY INVISIBLE (-3225 4000);
FORCEPROP 1 LAST BODY_TYPE PLUMBING
J 0
(-3225 4050);
DISPLAY 0.872340 (-3225 4050);
PAINT GREEN (-3225 4050);
DISPLAY INVISIBLE (-3225 4050);
FORCEPROP 1 LAST HDL_TAP TRUE
J 0
(-2900 3875);
DISPLAY 0.872340 (-2900 3875);
DISPLAY INVISIBLE (-2900 3875);
FORCEPROP 1 LAST PATH I197
J 0
(-3227 4000);
DISPLAY 0.872340 (-3227 4000);
PAINT GREEN (-3227 4000);
DISPLAY INVISIBLE (-3227 4000);
FORCEADD TAP..1
(-3225 3950);
FORCEPROP 3 LASTPIN (-3275 3950) SIG_NAME M_K_CPU1_SB_DQ<3>
J 0
(-3265 3960);
DISPLAY 0.659574 (-3265 3960);
PAINT MONO (-3265 3960);
DISPLAY INVISIBLE (-3265 3960);
FORCEPROP 1 LASTPIN (-3275 3950) BN 3
J 0
(-3287 3958);
DISPLAY 0.489362 (-3287 3958);
PAINT GREEN (-3287 3958);
FORCEPROP 2 LAST CDS_LIB mstr_standard
J 0
(-3225 3950);
DISPLAY 0.723404 (-3225 3950);
PAINT MONO (-3225 3950);
DISPLAY INVISIBLE (-3225 3950);
FORCEPROP 1 LAST BODY_TYPE PLUMBING
J 0
(-3225 4000);
DISPLAY 0.872340 (-3225 4000);
PAINT GREEN (-3225 4000);
DISPLAY INVISIBLE (-3225 4000);
FORCEPROP 1 LAST HDL_TAP TRUE
J 0
(-2900 3825);
DISPLAY 0.872340 (-2900 3825);
DISPLAY INVISIBLE (-2900 3825);
FORCEPROP 1 LAST PATH I198
J 0
(-3227 3950);
DISPLAY 0.872340 (-3227 3950);
PAINT GREEN (-3227 3950);
DISPLAY INVISIBLE (-3227 3950);
FORCEADD TAP..1
(-3225 3850);
FORCEPROP 3 LASTPIN (-3275 3850) SIG_NAME M_K_CPU1_SB_DQ<5>
J 0
(-3265 3860);
DISPLAY 0.659574 (-3265 3860);
PAINT MONO (-3265 3860);
DISPLAY INVISIBLE (-3265 3860);
FORCEPROP 1 LASTPIN (-3275 3850) BN 5
J 0
(-3287 3858);
DISPLAY 0.489362 (-3287 3858);
PAINT GREEN (-3287 3858);
FORCEPROP 2 LAST CDS_LIB mstr_standard
J 0
(-3225 3850);
DISPLAY 0.723404 (-3225 3850);
PAINT MONO (-3225 3850);
DISPLAY INVISIBLE (-3225 3850);
FORCEPROP 1 LAST BODY_TYPE PLUMBING
J 0
(-3225 3900);
DISPLAY 0.872340 (-3225 3900);
PAINT GREEN (-3225 3900);
DISPLAY INVISIBLE (-3225 3900);
FORCEPROP 1 LAST HDL_TAP TRUE
J 0
(-2900 3725);
DISPLAY 0.872340 (-2900 3725);
DISPLAY INVISIBLE (-2900 3725);
FORCEPROP 1 LAST PATH I199
J 0
(-3227 3850);
DISPLAY 0.872340 (-3227 3850);
PAINT GREEN (-3227 3850);
DISPLAY INVISIBLE (-3227 3850);
FORCEADD TAP..1
(-3225 3900);
FORCEPROP 3 LASTPIN (-3275 3900) SIG_NAME M_K_CPU1_SB_DQ<4>
J 0
(-3265 3910);
DISPLAY 0.659574 (-3265 3910);
PAINT MONO (-3265 3910);
DISPLAY INVISIBLE (-3265 3910);
FORCEPROP 1 LASTPIN (-3275 3900) BN 4
J 0
(-3287 3908);
DISPLAY 0.489362 (-3287 3908);
PAINT GREEN (-3287 3908);
FORCEPROP 2 LAST CDS_LIB mstr_standard
J 0
(-3225 3900);
DISPLAY 0.723404 (-3225 3900);
PAINT MONO (-3225 3900);
DISPLAY INVISIBLE (-3225 3900);
FORCEPROP 1 LAST BODY_TYPE PLUMBING
J 0
(-3225 3950);
DISPLAY 0.872340 (-3225 3950);
PAINT GREEN (-3225 3950);
DISPLAY INVISIBLE (-3225 3950);
FORCEPROP 1 LAST HDL_TAP TRUE
J 0
(-2900 3775);
DISPLAY 0.872340 (-2900 3775);
DISPLAY INVISIBLE (-2900 3775);
FORCEPROP 1 LAST PATH I200
J 0
(-3227 3900);
DISPLAY 0.872340 (-3227 3900);
PAINT GREEN (-3227 3900);
DISPLAY INVISIBLE (-3227 3900);
FORCEADD TAP..1
(-3225 3800);
FORCEPROP 3 LASTPIN (-3275 3800) SIG_NAME M_K_CPU1_SB_DQ<6>
J 0
(-3265 3810);
DISPLAY 0.659574 (-3265 3810);
PAINT MONO (-3265 3810);
DISPLAY INVISIBLE (-3265 3810);
FORCEPROP 1 LASTPIN (-3275 3800) BN 6
J 0
(-3287 3808);
DISPLAY 0.489362 (-3287 3808);
PAINT GREEN (-3287 3808);
FORCEPROP 2 LAST CDS_LIB mstr_standard
J 0
(-3225 3800);
DISPLAY 0.723404 (-3225 3800);
PAINT MONO (-3225 3800);
DISPLAY INVISIBLE (-3225 3800);
FORCEPROP 1 LAST BODY_TYPE PLUMBING
J 0
(-3225 3850);
DISPLAY 0.872340 (-3225 3850);
PAINT GREEN (-3225 3850);
DISPLAY INVISIBLE (-3225 3850);
FORCEPROP 1 LAST HDL_TAP TRUE
J 0
(-2900 3675);
DISPLAY 0.872340 (-2900 3675);
DISPLAY INVISIBLE (-2900 3675);
FORCEPROP 1 LAST PATH I201
J 0
(-3227 3800);
DISPLAY 0.872340 (-3227 3800);
PAINT GREEN (-3227 3800);
DISPLAY INVISIBLE (-3227 3800);
FORCEADD TAP..1
(-3225 3750);
FORCEPROP 3 LASTPIN (-3275 3750) SIG_NAME M_K_CPU1_SB_DQ<7>
J 0
(-3265 3760);
DISPLAY 0.659574 (-3265 3760);
PAINT MONO (-3265 3760);
DISPLAY INVISIBLE (-3265 3760);
FORCEPROP 1 LASTPIN (-3275 3750) BN 7
J 0
(-3287 3758);
DISPLAY 0.489362 (-3287 3758);
PAINT GREEN (-3287 3758);
FORCEPROP 2 LAST CDS_LIB mstr_standard
J 0
(-3225 3750);
DISPLAY 0.723404 (-3225 3750);
PAINT MONO (-3225 3750);
DISPLAY INVISIBLE (-3225 3750);
FORCEPROP 1 LAST BODY_TYPE PLUMBING
J 0
(-3225 3800);
DISPLAY 0.872340 (-3225 3800);
PAINT GREEN (-3225 3800);
DISPLAY INVISIBLE (-3225 3800);
FORCEPROP 1 LAST HDL_TAP TRUE
J 0
(-2900 3625);
DISPLAY 0.872340 (-2900 3625);
DISPLAY INVISIBLE (-2900 3625);
FORCEPROP 1 LAST PATH I202
J 0
(-3227 3750);
DISPLAY 0.872340 (-3227 3750);
PAINT GREEN (-3227 3750);
DISPLAY INVISIBLE (-3227 3750);
FORCEADD TAP..1
(-3225 3600);
FORCEPROP 3 LASTPIN (-3275 3600) SIG_NAME M_K_CPU1_SB_DQ<9>
J 0
(-3265 3610);
DISPLAY 0.659574 (-3265 3610);
PAINT MONO (-3265 3610);
DISPLAY INVISIBLE (-3265 3610);
FORCEPROP 1 LASTPIN (-3275 3600) BN 9
J 0
(-3287 3608);
DISPLAY 0.489362 (-3287 3608);
PAINT GREEN (-3287 3608);
FORCEPROP 2 LAST CDS_LIB mstr_standard
J 0
(-3225 3600);
DISPLAY 0.723404 (-3225 3600);
PAINT MONO (-3225 3600);
DISPLAY INVISIBLE (-3225 3600);
FORCEPROP 1 LAST BODY_TYPE PLUMBING
J 0
(-3225 3650);
DISPLAY 0.872340 (-3225 3650);
PAINT GREEN (-3225 3650);
DISPLAY INVISIBLE (-3225 3650);
FORCEPROP 1 LAST HDL_TAP TRUE
J 0
(-2900 3475);
DISPLAY 0.872340 (-2900 3475);
DISPLAY INVISIBLE (-2900 3475);
FORCEPROP 1 LAST PATH I203
J 0
(-3227 3600);
DISPLAY 0.872340 (-3227 3600);
PAINT GREEN (-3227 3600);
DISPLAY INVISIBLE (-3227 3600);
FORCEADD TAP..1
(-3225 3650);
FORCEPROP 3 LASTPIN (-3275 3650) SIG_NAME M_K_CPU1_SB_DQ<8>
J 0
(-3265 3660);
DISPLAY 0.659574 (-3265 3660);
PAINT MONO (-3265 3660);
DISPLAY INVISIBLE (-3265 3660);
FORCEPROP 1 LASTPIN (-3275 3650) BN 8
J 0
(-3287 3658);
DISPLAY 0.489362 (-3287 3658);
PAINT GREEN (-3287 3658);
FORCEPROP 2 LAST CDS_LIB mstr_standard
J 0
(-3225 3650);
DISPLAY 0.723404 (-3225 3650);
PAINT MONO (-3225 3650);
DISPLAY INVISIBLE (-3225 3650);
FORCEPROP 1 LAST BODY_TYPE PLUMBING
J 0
(-3225 3700);
DISPLAY 0.872340 (-3225 3700);
PAINT GREEN (-3225 3700);
DISPLAY INVISIBLE (-3225 3700);
FORCEPROP 1 LAST HDL_TAP TRUE
J 0
(-2900 3525);
DISPLAY 0.872340 (-2900 3525);
DISPLAY INVISIBLE (-2900 3525);
FORCEPROP 1 LAST PATH I204
J 0
(-3227 3650);
DISPLAY 0.872340 (-3227 3650);
PAINT GREEN (-3227 3650);
DISPLAY INVISIBLE (-3227 3650);
FORCEADD TAP..1
(-3225 3550);
FORCEPROP 3 LASTPIN (-3275 3550) SIG_NAME M_K_CPU1_SB_DQ<10>
J 0
(-3265 3560);
DISPLAY 0.659574 (-3265 3560);
PAINT MONO (-3265 3560);
DISPLAY INVISIBLE (-3265 3560);
FORCEPROP 1 LASTPIN (-3275 3550) BN 10
J 0
(-3287 3558);
DISPLAY 0.489362 (-3287 3558);
PAINT GREEN (-3287 3558);
FORCEPROP 2 LAST CDS_LIB mstr_standard
J 0
(-3225 3550);
DISPLAY 0.723404 (-3225 3550);
PAINT MONO (-3225 3550);
DISPLAY INVISIBLE (-3225 3550);
FORCEPROP 1 LAST BODY_TYPE PLUMBING
J 0
(-3225 3600);
DISPLAY 0.872340 (-3225 3600);
PAINT GREEN (-3225 3600);
DISPLAY INVISIBLE (-3225 3600);
FORCEPROP 1 LAST HDL_TAP TRUE
J 0
(-2900 3425);
DISPLAY 0.872340 (-2900 3425);
DISPLAY INVISIBLE (-2900 3425);
FORCEPROP 1 LAST PATH I205
J 0
(-3227 3550);
DISPLAY 0.872340 (-3227 3550);
PAINT GREEN (-3227 3550);
DISPLAY INVISIBLE (-3227 3550);
FORCEADD TAP..1
(-3225 3500);
FORCEPROP 3 LASTPIN (-3275 3500) SIG_NAME M_K_CPU1_SB_DQ<11>
J 0
(-3265 3510);
DISPLAY 0.659574 (-3265 3510);
PAINT MONO (-3265 3510);
DISPLAY INVISIBLE (-3265 3510);
FORCEPROP 1 LASTPIN (-3275 3500) BN 11
J 0
(-3287 3508);
DISPLAY 0.489362 (-3287 3508);
PAINT GREEN (-3287 3508);
FORCEPROP 2 LAST CDS_LIB mstr_standard
J 0
(-3225 3500);
DISPLAY 0.723404 (-3225 3500);
PAINT MONO (-3225 3500);
DISPLAY INVISIBLE (-3225 3500);
FORCEPROP 1 LAST BODY_TYPE PLUMBING
J 0
(-3225 3550);
DISPLAY 0.872340 (-3225 3550);
PAINT GREEN (-3225 3550);
DISPLAY INVISIBLE (-3225 3550);
FORCEPROP 1 LAST HDL_TAP TRUE
J 0
(-2900 3375);
DISPLAY 0.872340 (-2900 3375);
DISPLAY INVISIBLE (-2900 3375);
FORCEPROP 1 LAST PATH I206
J 0
(-3227 3500);
DISPLAY 0.872340 (-3227 3500);
PAINT GREEN (-3227 3500);
DISPLAY INVISIBLE (-3227 3500);
FORCEADD TAP..1
(-3225 3450);
FORCEPROP 3 LASTPIN (-3275 3450) SIG_NAME M_K_CPU1_SB_DQ<12>
J 0
(-3265 3460);
DISPLAY 0.659574 (-3265 3460);
PAINT MONO (-3265 3460);
DISPLAY INVISIBLE (-3265 3460);
FORCEPROP 1 LASTPIN (-3275 3450) BN 12
J 0
(-3287 3458);
DISPLAY 0.489362 (-3287 3458);
PAINT GREEN (-3287 3458);
FORCEPROP 2 LAST CDS_LIB mstr_standard
J 0
(-3225 3450);
DISPLAY 0.723404 (-3225 3450);
PAINT MONO (-3225 3450);
DISPLAY INVISIBLE (-3225 3450);
FORCEPROP 1 LAST BODY_TYPE PLUMBING
J 0
(-3225 3500);
DISPLAY 0.872340 (-3225 3500);
PAINT GREEN (-3225 3500);
DISPLAY INVISIBLE (-3225 3500);
FORCEPROP 1 LAST HDL_TAP TRUE
J 0
(-2900 3325);
DISPLAY 0.872340 (-2900 3325);
DISPLAY INVISIBLE (-2900 3325);
FORCEPROP 1 LAST PATH I207
J 0
(-3227 3450);
DISPLAY 0.872340 (-3227 3450);
PAINT GREEN (-3227 3450);
DISPLAY INVISIBLE (-3227 3450);
FORCEADD TAP..1
(-3225 3350);
FORCEPROP 3 LASTPIN (-3275 3350) SIG_NAME M_K_CPU1_SB_DQ<14>
J 0
(-3265 3360);
DISPLAY 0.659574 (-3265 3360);
PAINT MONO (-3265 3360);
DISPLAY INVISIBLE (-3265 3360);
FORCEPROP 1 LASTPIN (-3275 3350) BN 14
J 0
(-3287 3358);
DISPLAY 0.489362 (-3287 3358);
PAINT GREEN (-3287 3358);
FORCEPROP 2 LAST CDS_LIB mstr_standard
J 0
(-3225 3350);
DISPLAY 0.723404 (-3225 3350);
PAINT MONO (-3225 3350);
DISPLAY INVISIBLE (-3225 3350);
FORCEPROP 1 LAST BODY_TYPE PLUMBING
J 0
(-3225 3400);
DISPLAY 0.872340 (-3225 3400);
PAINT GREEN (-3225 3400);
DISPLAY INVISIBLE (-3225 3400);
FORCEPROP 1 LAST HDL_TAP TRUE
J 0
(-2900 3225);
DISPLAY 0.872340 (-2900 3225);
DISPLAY INVISIBLE (-2900 3225);
FORCEPROP 1 LAST PATH I208
J 0
(-3227 3350);
DISPLAY 0.872340 (-3227 3350);
PAINT GREEN (-3227 3350);
DISPLAY INVISIBLE (-3227 3350);
FORCEADD TAP..1
(-3225 3400);
FORCEPROP 3 LASTPIN (-3275 3400) SIG_NAME M_K_CPU1_SB_DQ<13>
J 0
(-3265 3410);
DISPLAY 0.659574 (-3265 3410);
PAINT MONO (-3265 3410);
DISPLAY INVISIBLE (-3265 3410);
FORCEPROP 1 LASTPIN (-3275 3400) BN 13
J 0
(-3287 3408);
DISPLAY 0.489362 (-3287 3408);
PAINT GREEN (-3287 3408);
FORCEPROP 2 LAST CDS_LIB mstr_standard
J 0
(-3225 3400);
DISPLAY 0.723404 (-3225 3400);
PAINT MONO (-3225 3400);
DISPLAY INVISIBLE (-3225 3400);
FORCEPROP 1 LAST BODY_TYPE PLUMBING
J 0
(-3225 3450);
DISPLAY 0.872340 (-3225 3450);
PAINT GREEN (-3225 3450);
DISPLAY INVISIBLE (-3225 3450);
FORCEPROP 1 LAST HDL_TAP TRUE
J 0
(-2900 3275);
DISPLAY 0.872340 (-2900 3275);
DISPLAY INVISIBLE (-2900 3275);
FORCEPROP 1 LAST PATH I209
J 0
(-3227 3400);
DISPLAY 0.872340 (-3227 3400);
PAINT GREEN (-3227 3400);
DISPLAY INVISIBLE (-3227 3400);
FORCEADD TAP..1
(-3225 3300);
FORCEPROP 3 LASTPIN (-3275 3300) SIG_NAME M_K_CPU1_SB_DQ<15>
J 0
(-3265 3310);
DISPLAY 0.659574 (-3265 3310);
PAINT MONO (-3265 3310);
DISPLAY INVISIBLE (-3265 3310);
FORCEPROP 1 LASTPIN (-3275 3300) BN 15
J 0
(-3287 3308);
DISPLAY 0.489362 (-3287 3308);
PAINT GREEN (-3287 3308);
FORCEPROP 2 LAST CDS_LIB mstr_standard
J 0
(-3225 3300);
DISPLAY 0.723404 (-3225 3300);
PAINT MONO (-3225 3300);
DISPLAY INVISIBLE (-3225 3300);
FORCEPROP 1 LAST BODY_TYPE PLUMBING
J 0
(-3225 3350);
DISPLAY 0.872340 (-3225 3350);
PAINT GREEN (-3225 3350);
DISPLAY INVISIBLE (-3225 3350);
FORCEPROP 1 LAST HDL_TAP TRUE
J 0
(-2900 3175);
DISPLAY 0.872340 (-2900 3175);
DISPLAY INVISIBLE (-2900 3175);
FORCEPROP 1 LAST PATH I210
J 0
(-3227 3300);
DISPLAY 0.872340 (-3227 3300);
PAINT GREEN (-3227 3300);
DISPLAY INVISIBLE (-3227 3300);
FORCEADD TAP..1
(-3225 3200);
FORCEPROP 3 LASTPIN (-3275 3200) SIG_NAME M_K_CPU1_SB_DQ<16>
J 0
(-3265 3210);
DISPLAY 0.659574 (-3265 3210);
PAINT MONO (-3265 3210);
DISPLAY INVISIBLE (-3265 3210);
FORCEPROP 1 LASTPIN (-3275 3200) BN 16
J 0
(-3287 3208);
DISPLAY 0.489362 (-3287 3208);
PAINT GREEN (-3287 3208);
FORCEPROP 2 LAST CDS_LIB mstr_standard
J 0
(-3225 3200);
DISPLAY 0.723404 (-3225 3200);
PAINT MONO (-3225 3200);
DISPLAY INVISIBLE (-3225 3200);
FORCEPROP 1 LAST BODY_TYPE PLUMBING
J 0
(-3225 3250);
DISPLAY 0.872340 (-3225 3250);
PAINT GREEN (-3225 3250);
DISPLAY INVISIBLE (-3225 3250);
FORCEPROP 1 LAST HDL_TAP TRUE
J 0
(-2900 3075);
DISPLAY 0.872340 (-2900 3075);
DISPLAY INVISIBLE (-2900 3075);
FORCEPROP 1 LAST PATH I211
J 0
(-3227 3200);
DISPLAY 0.872340 (-3227 3200);
PAINT GREEN (-3227 3200);
DISPLAY INVISIBLE (-3227 3200);
FORCEADD TAP..1
(-3225 3150);
FORCEPROP 3 LASTPIN (-3275 3150) SIG_NAME M_K_CPU1_SB_DQ<17>
J 0
(-3265 3160);
DISPLAY 0.659574 (-3265 3160);
PAINT MONO (-3265 3160);
DISPLAY INVISIBLE (-3265 3160);
FORCEPROP 1 LASTPIN (-3275 3150) BN 17
J 0
(-3287 3158);
DISPLAY 0.489362 (-3287 3158);
PAINT GREEN (-3287 3158);
FORCEPROP 2 LAST CDS_LIB mstr_standard
J 0
(-3225 3150);
DISPLAY 0.723404 (-3225 3150);
PAINT MONO (-3225 3150);
DISPLAY INVISIBLE (-3225 3150);
FORCEPROP 1 LAST BODY_TYPE PLUMBING
J 0
(-3225 3200);
DISPLAY 0.872340 (-3225 3200);
PAINT GREEN (-3225 3200);
DISPLAY INVISIBLE (-3225 3200);
FORCEPROP 1 LAST HDL_TAP TRUE
J 0
(-2900 3025);
DISPLAY 0.872340 (-2900 3025);
DISPLAY INVISIBLE (-2900 3025);
FORCEPROP 1 LAST PATH I212
J 0
(-3227 3150);
DISPLAY 0.872340 (-3227 3150);
PAINT GREEN (-3227 3150);
DISPLAY INVISIBLE (-3227 3150);
FORCEADD TAP..1
(-3225 3100);
FORCEPROP 3 LASTPIN (-3275 3100) SIG_NAME M_K_CPU1_SB_DQ<18>
J 0
(-3265 3110);
DISPLAY 0.659574 (-3265 3110);
PAINT MONO (-3265 3110);
DISPLAY INVISIBLE (-3265 3110);
FORCEPROP 1 LASTPIN (-3275 3100) BN 18
J 0
(-3287 3108);
DISPLAY 0.489362 (-3287 3108);
PAINT GREEN (-3287 3108);
FORCEPROP 2 LAST CDS_LIB mstr_standard
J 0
(-3225 3100);
DISPLAY 0.723404 (-3225 3100);
PAINT MONO (-3225 3100);
DISPLAY INVISIBLE (-3225 3100);
FORCEPROP 1 LAST BODY_TYPE PLUMBING
J 0
(-3225 3150);
DISPLAY 0.872340 (-3225 3150);
PAINT GREEN (-3225 3150);
DISPLAY INVISIBLE (-3225 3150);
FORCEPROP 1 LAST HDL_TAP TRUE
J 0
(-2900 2975);
DISPLAY 0.872340 (-2900 2975);
DISPLAY INVISIBLE (-2900 2975);
FORCEPROP 1 LAST PATH I213
J 0
(-3227 3100);
DISPLAY 0.872340 (-3227 3100);
PAINT GREEN (-3227 3100);
DISPLAY INVISIBLE (-3227 3100);
FORCEADD TAP..1
(-3225 3050);
FORCEPROP 3 LASTPIN (-3275 3050) SIG_NAME M_K_CPU1_SB_DQ<19>
J 0
(-3265 3060);
DISPLAY 0.659574 (-3265 3060);
PAINT MONO (-3265 3060);
DISPLAY INVISIBLE (-3265 3060);
FORCEPROP 1 LASTPIN (-3275 3050) BN 19
J 0
(-3287 3058);
DISPLAY 0.489362 (-3287 3058);
PAINT GREEN (-3287 3058);
FORCEPROP 2 LAST CDS_LIB mstr_standard
J 0
(-3225 3050);
DISPLAY 0.723404 (-3225 3050);
PAINT MONO (-3225 3050);
DISPLAY INVISIBLE (-3225 3050);
FORCEPROP 1 LAST BODY_TYPE PLUMBING
J 0
(-3225 3100);
DISPLAY 0.872340 (-3225 3100);
PAINT GREEN (-3225 3100);
DISPLAY INVISIBLE (-3225 3100);
FORCEPROP 1 LAST HDL_TAP TRUE
J 0
(-2900 2925);
DISPLAY 0.872340 (-2900 2925);
DISPLAY INVISIBLE (-2900 2925);
FORCEPROP 1 LAST PATH I214
J 0
(-3227 3050);
DISPLAY 0.872340 (-3227 3050);
PAINT GREEN (-3227 3050);
DISPLAY INVISIBLE (-3227 3050);
FORCEADD TAP..1
(-3225 2950);
FORCEPROP 3 LASTPIN (-3275 2950) SIG_NAME M_K_CPU1_SB_DQ<21>
J 0
(-3265 2960);
DISPLAY 0.659574 (-3265 2960);
PAINT MONO (-3265 2960);
DISPLAY INVISIBLE (-3265 2960);
FORCEPROP 1 LASTPIN (-3275 2950) BN 21
J 0
(-3287 2958);
DISPLAY 0.489362 (-3287 2958);
PAINT GREEN (-3287 2958);
FORCEPROP 2 LAST CDS_LIB mstr_standard
J 0
(-3225 2950);
DISPLAY 0.723404 (-3225 2950);
PAINT MONO (-3225 2950);
DISPLAY INVISIBLE (-3225 2950);
FORCEPROP 1 LAST BODY_TYPE PLUMBING
J 0
(-3225 3000);
DISPLAY 0.872340 (-3225 3000);
PAINT GREEN (-3225 3000);
DISPLAY INVISIBLE (-3225 3000);
FORCEPROP 1 LAST HDL_TAP TRUE
J 0
(-2900 2825);
DISPLAY 0.872340 (-2900 2825);
DISPLAY INVISIBLE (-2900 2825);
FORCEPROP 1 LAST PATH I215
J 0
(-3227 2950);
DISPLAY 0.872340 (-3227 2950);
PAINT GREEN (-3227 2950);
DISPLAY INVISIBLE (-3227 2950);
FORCEADD TAP..1
(-3225 3000);
FORCEPROP 3 LASTPIN (-3275 3000) SIG_NAME M_K_CPU1_SB_DQ<20>
J 0
(-3265 3010);
DISPLAY 0.659574 (-3265 3010);
PAINT MONO (-3265 3010);
DISPLAY INVISIBLE (-3265 3010);
FORCEPROP 1 LASTPIN (-3275 3000) BN 20
J 0
(-3287 3008);
DISPLAY 0.489362 (-3287 3008);
PAINT GREEN (-3287 3008);
FORCEPROP 2 LAST CDS_LIB mstr_standard
J 0
(-3225 3000);
DISPLAY 0.723404 (-3225 3000);
PAINT MONO (-3225 3000);
DISPLAY INVISIBLE (-3225 3000);
FORCEPROP 1 LAST BODY_TYPE PLUMBING
J 0
(-3225 3050);
DISPLAY 0.872340 (-3225 3050);
PAINT GREEN (-3225 3050);
DISPLAY INVISIBLE (-3225 3050);
FORCEPROP 1 LAST HDL_TAP TRUE
J 0
(-2900 2875);
DISPLAY 0.872340 (-2900 2875);
DISPLAY INVISIBLE (-2900 2875);
FORCEPROP 1 LAST PATH I216
J 0
(-3227 3000);
DISPLAY 0.872340 (-3227 3000);
PAINT GREEN (-3227 3000);
DISPLAY INVISIBLE (-3227 3000);
FORCEADD TAP..1
(-3225 2900);
FORCEPROP 3 LASTPIN (-3275 2900) SIG_NAME M_K_CPU1_SB_DQ<22>
J 0
(-3265 2910);
DISPLAY 0.659574 (-3265 2910);
PAINT MONO (-3265 2910);
DISPLAY INVISIBLE (-3265 2910);
FORCEPROP 1 LASTPIN (-3275 2900) BN 22
J 0
(-3287 2908);
DISPLAY 0.489362 (-3287 2908);
PAINT GREEN (-3287 2908);
FORCEPROP 2 LAST CDS_LIB mstr_standard
J 0
(-3225 2900);
DISPLAY 0.723404 (-3225 2900);
PAINT MONO (-3225 2900);
DISPLAY INVISIBLE (-3225 2900);
FORCEPROP 1 LAST BODY_TYPE PLUMBING
J 0
(-3225 2950);
DISPLAY 0.872340 (-3225 2950);
PAINT GREEN (-3225 2950);
DISPLAY INVISIBLE (-3225 2950);
FORCEPROP 1 LAST HDL_TAP TRUE
J 0
(-2900 2775);
DISPLAY 0.872340 (-2900 2775);
DISPLAY INVISIBLE (-2900 2775);
FORCEPROP 1 LAST PATH I217
J 0
(-3227 2900);
DISPLAY 0.872340 (-3227 2900);
PAINT GREEN (-3227 2900);
DISPLAY INVISIBLE (-3227 2900);
FORCEADD TAP..1
(-3225 2850);
FORCEPROP 3 LASTPIN (-3275 2850) SIG_NAME M_K_CPU1_SB_DQ<23>
J 0
(-3265 2860);
DISPLAY 0.659574 (-3265 2860);
PAINT MONO (-3265 2860);
DISPLAY INVISIBLE (-3265 2860);
FORCEPROP 1 LASTPIN (-3275 2850) BN 23
J 0
(-3287 2858);
DISPLAY 0.489362 (-3287 2858);
PAINT GREEN (-3287 2858);
FORCEPROP 2 LAST CDS_LIB mstr_standard
J 0
(-3225 2850);
DISPLAY 0.723404 (-3225 2850);
PAINT MONO (-3225 2850);
DISPLAY INVISIBLE (-3225 2850);
FORCEPROP 1 LAST BODY_TYPE PLUMBING
J 0
(-3225 2900);
DISPLAY 0.872340 (-3225 2900);
PAINT GREEN (-3225 2900);
DISPLAY INVISIBLE (-3225 2900);
FORCEPROP 1 LAST HDL_TAP TRUE
J 0
(-2900 2725);
DISPLAY 0.872340 (-2900 2725);
DISPLAY INVISIBLE (-2900 2725);
FORCEPROP 1 LAST PATH I218
J 0
(-3227 2850);
DISPLAY 0.872340 (-3227 2850);
PAINT GREEN (-3227 2850);
DISPLAY INVISIBLE (-3227 2850);
FORCEADD TAP..1
(-3225 2750);
FORCEPROP 3 LASTPIN (-3275 2750) SIG_NAME M_K_CPU1_SB_DQ<24>
J 0
(-3265 2760);
DISPLAY 0.659574 (-3265 2760);
PAINT MONO (-3265 2760);
DISPLAY INVISIBLE (-3265 2760);
FORCEPROP 1 LASTPIN (-3275 2750) BN 24
J 0
(-3287 2758);
DISPLAY 0.489362 (-3287 2758);
PAINT GREEN (-3287 2758);
FORCEPROP 2 LAST CDS_LIB mstr_standard
J 0
(-3225 2750);
DISPLAY 0.723404 (-3225 2750);
PAINT MONO (-3225 2750);
DISPLAY INVISIBLE (-3225 2750);
FORCEPROP 1 LAST BODY_TYPE PLUMBING
J 0
(-3225 2800);
DISPLAY 0.872340 (-3225 2800);
PAINT GREEN (-3225 2800);
DISPLAY INVISIBLE (-3225 2800);
FORCEPROP 1 LAST HDL_TAP TRUE
J 0
(-2900 2625);
DISPLAY 0.872340 (-2900 2625);
DISPLAY INVISIBLE (-2900 2625);
FORCEPROP 1 LAST PATH I219
J 0
(-3227 2750);
DISPLAY 0.872340 (-3227 2750);
PAINT GREEN (-3227 2750);
DISPLAY INVISIBLE (-3227 2750);
FORCEADD TAP..1
(-3225 2700);
FORCEPROP 3 LASTPIN (-3275 2700) SIG_NAME M_K_CPU1_SB_DQ<25>
J 0
(-3265 2710);
DISPLAY 0.659574 (-3265 2710);
PAINT MONO (-3265 2710);
DISPLAY INVISIBLE (-3265 2710);
FORCEPROP 1 LASTPIN (-3275 2700) BN 25
J 0
(-3287 2708);
DISPLAY 0.489362 (-3287 2708);
PAINT GREEN (-3287 2708);
FORCEPROP 2 LAST CDS_LIB mstr_standard
J 0
(-3225 2700);
DISPLAY 0.723404 (-3225 2700);
PAINT MONO (-3225 2700);
DISPLAY INVISIBLE (-3225 2700);
FORCEPROP 1 LAST BODY_TYPE PLUMBING
J 0
(-3225 2750);
DISPLAY 0.872340 (-3225 2750);
PAINT GREEN (-3225 2750);
DISPLAY INVISIBLE (-3225 2750);
FORCEPROP 1 LAST HDL_TAP TRUE
J 0
(-2900 2575);
DISPLAY 0.872340 (-2900 2575);
DISPLAY INVISIBLE (-2900 2575);
FORCEPROP 1 LAST PATH I220
J 0
(-3227 2700);
DISPLAY 0.872340 (-3227 2700);
PAINT GREEN (-3227 2700);
DISPLAY INVISIBLE (-3227 2700);
FORCEADD TAP..1
(-3225 2650);
FORCEPROP 3 LASTPIN (-3275 2650) SIG_NAME M_K_CPU1_SB_DQ<26>
J 0
(-3265 2660);
DISPLAY 0.659574 (-3265 2660);
PAINT MONO (-3265 2660);
DISPLAY INVISIBLE (-3265 2660);
FORCEPROP 1 LASTPIN (-3275 2650) BN 26
J 0
(-3287 2658);
DISPLAY 0.489362 (-3287 2658);
PAINT GREEN (-3287 2658);
FORCEPROP 2 LAST CDS_LIB mstr_standard
J 0
(-3225 2650);
DISPLAY 0.723404 (-3225 2650);
PAINT MONO (-3225 2650);
DISPLAY INVISIBLE (-3225 2650);
FORCEPROP 1 LAST BODY_TYPE PLUMBING
J 0
(-3225 2700);
DISPLAY 0.872340 (-3225 2700);
PAINT GREEN (-3225 2700);
DISPLAY INVISIBLE (-3225 2700);
FORCEPROP 1 LAST HDL_TAP TRUE
J 0
(-2900 2525);
DISPLAY 0.872340 (-2900 2525);
DISPLAY INVISIBLE (-2900 2525);
FORCEPROP 1 LAST PATH I221
J 0
(-3227 2650);
DISPLAY 0.872340 (-3227 2650);
PAINT GREEN (-3227 2650);
DISPLAY INVISIBLE (-3227 2650);
FORCEADD TAP..1
(-3225 2600);
FORCEPROP 3 LASTPIN (-3275 2600) SIG_NAME M_K_CPU1_SB_DQ<27>
J 0
(-3265 2610);
DISPLAY 0.659574 (-3265 2610);
PAINT MONO (-3265 2610);
DISPLAY INVISIBLE (-3265 2610);
FORCEPROP 1 LASTPIN (-3275 2600) BN 27
J 0
(-3287 2608);
DISPLAY 0.489362 (-3287 2608);
PAINT GREEN (-3287 2608);
FORCEPROP 2 LAST CDS_LIB mstr_standard
J 0
(-3225 2600);
DISPLAY 0.723404 (-3225 2600);
PAINT MONO (-3225 2600);
DISPLAY INVISIBLE (-3225 2600);
FORCEPROP 1 LAST BODY_TYPE PLUMBING
J 0
(-3225 2650);
DISPLAY 0.872340 (-3225 2650);
PAINT GREEN (-3225 2650);
DISPLAY INVISIBLE (-3225 2650);
FORCEPROP 1 LAST HDL_TAP TRUE
J 0
(-2900 2475);
DISPLAY 0.872340 (-2900 2475);
DISPLAY INVISIBLE (-2900 2475);
FORCEPROP 1 LAST PATH I222
J 0
(-3227 2600);
DISPLAY 0.872340 (-3227 2600);
PAINT GREEN (-3227 2600);
DISPLAY INVISIBLE (-3227 2600);
FORCEADD TAP..1
(-3225 2500);
FORCEPROP 3 LASTPIN (-3275 2500) SIG_NAME M_K_CPU1_SB_DQ<29>
J 0
(-3265 2510);
DISPLAY 0.659574 (-3265 2510);
PAINT MONO (-3265 2510);
DISPLAY INVISIBLE (-3265 2510);
FORCEPROP 1 LASTPIN (-3275 2500) BN 29
J 0
(-3287 2508);
DISPLAY 0.489362 (-3287 2508);
PAINT GREEN (-3287 2508);
FORCEPROP 2 LAST CDS_LIB mstr_standard
J 0
(-3225 2500);
DISPLAY 0.723404 (-3225 2500);
PAINT MONO (-3225 2500);
DISPLAY INVISIBLE (-3225 2500);
FORCEPROP 1 LAST BODY_TYPE PLUMBING
J 0
(-3225 2550);
DISPLAY 0.872340 (-3225 2550);
PAINT GREEN (-3225 2550);
DISPLAY INVISIBLE (-3225 2550);
FORCEPROP 1 LAST HDL_TAP TRUE
J 0
(-2900 2375);
DISPLAY 0.872340 (-2900 2375);
DISPLAY INVISIBLE (-2900 2375);
FORCEPROP 1 LAST PATH I223
J 0
(-3227 2500);
DISPLAY 0.872340 (-3227 2500);
PAINT GREEN (-3227 2500);
DISPLAY INVISIBLE (-3227 2500);
FORCEADD TAP..1
(-3225 2550);
FORCEPROP 3 LASTPIN (-3275 2550) SIG_NAME M_K_CPU1_SB_DQ<28>
J 0
(-3265 2560);
DISPLAY 0.659574 (-3265 2560);
PAINT MONO (-3265 2560);
DISPLAY INVISIBLE (-3265 2560);
FORCEPROP 1 LASTPIN (-3275 2550) BN 28
J 0
(-3287 2558);
DISPLAY 0.489362 (-3287 2558);
PAINT GREEN (-3287 2558);
FORCEPROP 2 LAST CDS_LIB mstr_standard
J 0
(-3225 2550);
DISPLAY 0.723404 (-3225 2550);
PAINT MONO (-3225 2550);
DISPLAY INVISIBLE (-3225 2550);
FORCEPROP 1 LAST BODY_TYPE PLUMBING
J 0
(-3225 2600);
DISPLAY 0.872340 (-3225 2600);
PAINT GREEN (-3225 2600);
DISPLAY INVISIBLE (-3225 2600);
FORCEPROP 1 LAST HDL_TAP TRUE
J 0
(-2900 2425);
DISPLAY 0.872340 (-2900 2425);
DISPLAY INVISIBLE (-2900 2425);
FORCEPROP 1 LAST PATH I224
J 0
(-3227 2550);
DISPLAY 0.872340 (-3227 2550);
PAINT GREEN (-3227 2550);
DISPLAY INVISIBLE (-3227 2550);
FORCEADD TAP..1
(-3225 2450);
FORCEPROP 3 LASTPIN (-3275 2450) SIG_NAME M_K_CPU1_SB_DQ<30>
J 0
(-3265 2460);
DISPLAY 0.659574 (-3265 2460);
PAINT MONO (-3265 2460);
DISPLAY INVISIBLE (-3265 2460);
FORCEPROP 1 LASTPIN (-3275 2450) BN 30
J 0
(-3287 2458);
DISPLAY 0.489362 (-3287 2458);
PAINT GREEN (-3287 2458);
FORCEPROP 2 LAST CDS_LIB mstr_standard
J 0
(-3225 2450);
DISPLAY 0.723404 (-3225 2450);
PAINT MONO (-3225 2450);
DISPLAY INVISIBLE (-3225 2450);
FORCEPROP 1 LAST BODY_TYPE PLUMBING
J 0
(-3225 2500);
DISPLAY 0.872340 (-3225 2500);
PAINT GREEN (-3225 2500);
DISPLAY INVISIBLE (-3225 2500);
FORCEPROP 1 LAST HDL_TAP TRUE
J 0
(-2900 2325);
DISPLAY 0.872340 (-2900 2325);
DISPLAY INVISIBLE (-2900 2325);
FORCEPROP 1 LAST PATH I225
J 0
(-3227 2450);
DISPLAY 0.872340 (-3227 2450);
PAINT GREEN (-3227 2450);
DISPLAY INVISIBLE (-3227 2450);
FORCEADD TAP..1
(-3225 2400);
FORCEPROP 3 LASTPIN (-3275 2400) SIG_NAME M_K_CPU1_SB_DQ<31>
J 0
(-3265 2410);
DISPLAY 0.659574 (-3265 2410);
PAINT MONO (-3265 2410);
DISPLAY INVISIBLE (-3265 2410);
FORCEPROP 1 LASTPIN (-3275 2400) BN 31
J 0
(-3287 2408);
DISPLAY 0.489362 (-3287 2408);
PAINT GREEN (-3287 2408);
FORCEPROP 2 LAST CDS_LIB mstr_standard
J 0
(-3225 2400);
DISPLAY 0.723404 (-3225 2400);
PAINT MONO (-3225 2400);
DISPLAY INVISIBLE (-3225 2400);
FORCEPROP 1 LAST BODY_TYPE PLUMBING
J 0
(-3225 2450);
DISPLAY 0.872340 (-3225 2450);
PAINT GREEN (-3225 2450);
DISPLAY INVISIBLE (-3225 2450);
FORCEPROP 1 LAST HDL_TAP TRUE
J 0
(-2900 2275);
DISPLAY 0.872340 (-2900 2275);
DISPLAY INVISIBLE (-2900 2275);
FORCEPROP 1 LAST PATH I226
J 0
(-3227 2400);
DISPLAY 0.872340 (-3227 2400);
PAINT GREEN (-3227 2400);
DISPLAY INVISIBLE (-3227 2400);
FORCEADD TAP..1
(-3225 2300);
FORCEPROP 3 LASTPIN (-3275 2300) SIG_NAME M_K_CPU1_SA_CB<0>
J 0
(-3265 2310);
DISPLAY 0.659574 (-3265 2310);
PAINT MONO (-3265 2310);
DISPLAY INVISIBLE (-3265 2310);
FORCEPROP 1 LASTPIN (-3275 2300) BN 0
J 0
(-3287 2308);
DISPLAY 0.489362 (-3287 2308);
PAINT GREEN (-3287 2308);
FORCEPROP 2 LAST CDS_LIB mstr_standard
J 2
(-3225 2300);
DISPLAY 0.723404 (-3225 2300);
PAINT MONO (-3225 2300);
DISPLAY INVISIBLE (-3225 2300);
FORCEPROP 1 LAST BODY_TYPE PLUMBING
J 0
(-3225 2350);
DISPLAY 0.872340 (-3225 2350);
PAINT GREEN (-3225 2350);
DISPLAY INVISIBLE (-3225 2350);
FORCEPROP 1 LAST HDL_TAP TRUE
J 0
(-2900 2175);
DISPLAY 0.872340 (-2900 2175);
DISPLAY INVISIBLE (-2900 2175);
FORCEPROP 1 LAST PATH I227
J 0
(-3227 2300);
DISPLAY 0.872340 (-3227 2300);
PAINT GREEN (-3227 2300);
DISPLAY INVISIBLE (-3227 2300);
FORCEADD TAP..1
(-3225 2250);
FORCEPROP 3 LASTPIN (-3275 2250) SIG_NAME M_K_CPU1_SA_CB<1>
J 0
(-3265 2260);
DISPLAY 0.659574 (-3265 2260);
PAINT MONO (-3265 2260);
DISPLAY INVISIBLE (-3265 2260);
FORCEPROP 1 LASTPIN (-3275 2250) BN 1
J 0
(-3287 2258);
DISPLAY 0.489362 (-3287 2258);
PAINT GREEN (-3287 2258);
FORCEPROP 2 LAST CDS_LIB mstr_standard
J 2
(-3225 2250);
DISPLAY 0.723404 (-3225 2250);
PAINT MONO (-3225 2250);
DISPLAY INVISIBLE (-3225 2250);
FORCEPROP 1 LAST BODY_TYPE PLUMBING
J 0
(-3225 2300);
DISPLAY 0.872340 (-3225 2300);
PAINT GREEN (-3225 2300);
DISPLAY INVISIBLE (-3225 2300);
FORCEPROP 1 LAST HDL_TAP TRUE
J 0
(-2900 2125);
DISPLAY 0.872340 (-2900 2125);
DISPLAY INVISIBLE (-2900 2125);
FORCEPROP 1 LAST PATH I228
J 0
(-3227 2250);
DISPLAY 0.872340 (-3227 2250);
PAINT GREEN (-3227 2250);
DISPLAY INVISIBLE (-3227 2250);
FORCEADD TAP..1
(-3225 2200);
FORCEPROP 3 LASTPIN (-3275 2200) SIG_NAME M_K_CPU1_SA_CB<2>
J 0
(-3265 2210);
DISPLAY 0.659574 (-3265 2210);
PAINT MONO (-3265 2210);
DISPLAY INVISIBLE (-3265 2210);
FORCEPROP 1 LASTPIN (-3275 2200) BN 2
J 0
(-3287 2208);
DISPLAY 0.489362 (-3287 2208);
PAINT GREEN (-3287 2208);
FORCEPROP 2 LAST CDS_LIB mstr_standard
J 2
(-3225 2200);
DISPLAY 0.723404 (-3225 2200);
PAINT MONO (-3225 2200);
DISPLAY INVISIBLE (-3225 2200);
FORCEPROP 1 LAST BODY_TYPE PLUMBING
J 0
(-3225 2250);
DISPLAY 0.872340 (-3225 2250);
PAINT GREEN (-3225 2250);
DISPLAY INVISIBLE (-3225 2250);
FORCEPROP 1 LAST HDL_TAP TRUE
J 0
(-2900 2075);
DISPLAY 0.872340 (-2900 2075);
DISPLAY INVISIBLE (-2900 2075);
FORCEPROP 1 LAST PATH I229
J 0
(-3227 2200);
DISPLAY 0.872340 (-3227 2200);
PAINT GREEN (-3227 2200);
DISPLAY INVISIBLE (-3227 2200);
FORCEADD TAP..1
(-3225 2150);
FORCEPROP 3 LASTPIN (-3275 2150) SIG_NAME M_K_CPU1_SA_CB<3>
J 0
(-3265 2160);
DISPLAY 0.659574 (-3265 2160);
PAINT MONO (-3265 2160);
DISPLAY INVISIBLE (-3265 2160);
FORCEPROP 1 LASTPIN (-3275 2150) BN 3
J 0
(-3287 2158);
DISPLAY 0.489362 (-3287 2158);
PAINT GREEN (-3287 2158);
FORCEPROP 2 LAST CDS_LIB mstr_standard
J 2
(-3225 2150);
DISPLAY 0.723404 (-3225 2150);
PAINT MONO (-3225 2150);
DISPLAY INVISIBLE (-3225 2150);
FORCEPROP 1 LAST BODY_TYPE PLUMBING
J 0
(-3225 2200);
DISPLAY 0.872340 (-3225 2200);
PAINT GREEN (-3225 2200);
DISPLAY INVISIBLE (-3225 2200);
FORCEPROP 1 LAST HDL_TAP TRUE
J 0
(-2900 2025);
DISPLAY 0.872340 (-2900 2025);
DISPLAY INVISIBLE (-2900 2025);
FORCEPROP 1 LAST PATH I230
J 0
(-3227 2150);
DISPLAY 0.872340 (-3227 2150);
PAINT GREEN (-3227 2150);
DISPLAY INVISIBLE (-3227 2150);
FORCEADD TAP..1
(-3225 2100);
FORCEPROP 3 LASTPIN (-3275 2100) SIG_NAME M_K_CPU1_SA_CB<4>
J 0
(-3265 2110);
DISPLAY 0.659574 (-3265 2110);
PAINT MONO (-3265 2110);
DISPLAY INVISIBLE (-3265 2110);
FORCEPROP 1 LASTPIN (-3275 2100) BN 4
J 0
(-3287 2108);
DISPLAY 0.489362 (-3287 2108);
PAINT GREEN (-3287 2108);
FORCEPROP 2 LAST CDS_LIB mstr_standard
J 2
(-3225 2100);
DISPLAY 0.723404 (-3225 2100);
PAINT MONO (-3225 2100);
DISPLAY INVISIBLE (-3225 2100);
FORCEPROP 1 LAST BODY_TYPE PLUMBING
J 0
(-3225 2150);
DISPLAY 0.872340 (-3225 2150);
PAINT GREEN (-3225 2150);
DISPLAY INVISIBLE (-3225 2150);
FORCEPROP 1 LAST HDL_TAP TRUE
J 0
(-2900 1975);
DISPLAY 0.872340 (-2900 1975);
DISPLAY INVISIBLE (-2900 1975);
FORCEPROP 1 LAST PATH I231
J 0
(-3227 2100);
DISPLAY 0.872340 (-3227 2100);
PAINT GREEN (-3227 2100);
DISPLAY INVISIBLE (-3227 2100);
FORCEADD TAP..1
(-3225 2050);
FORCEPROP 3 LASTPIN (-3275 2050) SIG_NAME M_K_CPU1_SA_CB<5>
J 0
(-3265 2060);
DISPLAY 0.659574 (-3265 2060);
PAINT MONO (-3265 2060);
DISPLAY INVISIBLE (-3265 2060);
FORCEPROP 1 LASTPIN (-3275 2050) BN 5
J 0
(-3287 2058);
DISPLAY 0.489362 (-3287 2058);
PAINT GREEN (-3287 2058);
FORCEPROP 2 LAST CDS_LIB mstr_standard
J 2
(-3225 2050);
DISPLAY 0.723404 (-3225 2050);
PAINT MONO (-3225 2050);
DISPLAY INVISIBLE (-3225 2050);
FORCEPROP 1 LAST BODY_TYPE PLUMBING
J 0
(-3225 2100);
DISPLAY 0.872340 (-3225 2100);
PAINT GREEN (-3225 2100);
DISPLAY INVISIBLE (-3225 2100);
FORCEPROP 1 LAST HDL_TAP TRUE
J 0
(-2900 1925);
DISPLAY 0.872340 (-2900 1925);
DISPLAY INVISIBLE (-2900 1925);
FORCEPROP 1 LAST PATH I232
J 0
(-3227 2050);
DISPLAY 0.872340 (-3227 2050);
PAINT GREEN (-3227 2050);
DISPLAY INVISIBLE (-3227 2050);
FORCEADD OFFPAGE..6
R 2
(-2625 1900);
FORCEPROP 2 LAST $XR0 107 
J 0
(-2411 1900);
DISPLAY 0.638298 (-2411 1900);
PAINT MONO (-2411 1900);
FORCEPROP 2 LAST PATH I233
J 0
(-2400 1950);
DISPLAY 1.021277 (-2400 1950);
DISPLAY INVISIBLE (-2400 1950);
FORCEPROP 1 LAST COMMENT_BODY TRUE
J 2
(-2725 1825);
DISPLAY 0.872340 (-2725 1825);
PAINT GREEN (-2725 1825);
DISPLAY INVISIBLE (-2725 1825);
FORCEPROP 1 LAST OFFPAGE TRUE
J 2
(-2950 1775);
DISPLAY 0.872340 (-2950 1775);
PAINT GREEN (-2950 1775);
DISPLAY INVISIBLE (-2950 1775);
FORCEPROP 2 LAST CDS_LIB mstr_standard
J 2
(-2625 1900);
DISPLAY 0.723404 (-2625 1900);
PAINT MONO (-2625 1900);
DISPLAY INVISIBLE (-2625 1900);
FORCEADD TAP..1
(-3225 2000);
FORCEPROP 3 LASTPIN (-3275 2000) SIG_NAME M_K_CPU1_SA_CB<6>
J 0
(-3265 2010);
DISPLAY 0.659574 (-3265 2010);
PAINT MONO (-3265 2010);
DISPLAY INVISIBLE (-3265 2010);
FORCEPROP 1 LASTPIN (-3275 2000) BN 6
J 0
(-3287 2008);
DISPLAY 0.489362 (-3287 2008);
PAINT GREEN (-3287 2008);
FORCEPROP 2 LAST CDS_LIB mstr_standard
J 2
(-3225 2000);
DISPLAY 0.723404 (-3225 2000);
PAINT MONO (-3225 2000);
DISPLAY INVISIBLE (-3225 2000);
FORCEPROP 1 LAST BODY_TYPE PLUMBING
J 0
(-3225 2050);
DISPLAY 0.872340 (-3225 2050);
PAINT GREEN (-3225 2050);
DISPLAY INVISIBLE (-3225 2050);
FORCEPROP 1 LAST HDL_TAP TRUE
J 0
(-2900 1875);
DISPLAY 0.872340 (-2900 1875);
DISPLAY INVISIBLE (-2900 1875);
FORCEPROP 1 LAST PATH I234
J 0
(-3227 2000);
DISPLAY 0.872340 (-3227 2000);
PAINT GREEN (-3227 2000);
DISPLAY INVISIBLE (-3227 2000);
FORCEADD TAP..1
(-3225 1950);
FORCEPROP 3 LASTPIN (-3275 1950) SIG_NAME M_K_CPU1_SA_CB<7>
J 0
(-3265 1960);
DISPLAY 0.659574 (-3265 1960);
PAINT MONO (-3265 1960);
DISPLAY INVISIBLE (-3265 1960);
FORCEPROP 1 LASTPIN (-3275 1950) BN 7
J 0
(-3287 1958);
DISPLAY 0.489362 (-3287 1958);
PAINT GREEN (-3287 1958);
FORCEPROP 2 LAST CDS_LIB mstr_standard
J 2
(-3225 1950);
DISPLAY 0.723404 (-3225 1950);
PAINT MONO (-3225 1950);
DISPLAY INVISIBLE (-3225 1950);
FORCEPROP 1 LAST BODY_TYPE PLUMBING
J 0
(-3225 2000);
DISPLAY 0.872340 (-3225 2000);
PAINT GREEN (-3225 2000);
DISPLAY INVISIBLE (-3225 2000);
FORCEPROP 1 LAST HDL_TAP TRUE
J 0
(-2900 1825);
DISPLAY 0.872340 (-2900 1825);
DISPLAY INVISIBLE (-2900 1825);
FORCEPROP 1 LAST PATH I235
J 0
(-3227 1950);
DISPLAY 0.872340 (-3227 1950);
PAINT GREEN (-3227 1950);
DISPLAY INVISIBLE (-3227 1950);
FORCEADD TAP..1
(-3225 1800);
FORCEPROP 3 LASTPIN (-3275 1800) SIG_NAME M_K_CPU1_SB_CB<1>
J 0
(-3265 1810);
DISPLAY 0.659574 (-3265 1810);
PAINT MONO (-3265 1810);
DISPLAY INVISIBLE (-3265 1810);
FORCEPROP 1 LASTPIN (-3275 1800) BN 1
J 0
(-3287 1808);
DISPLAY 0.489362 (-3287 1808);
PAINT GREEN (-3287 1808);
FORCEPROP 2 LAST CDS_LIB mstr_standard
J 2
(-3225 1800);
DISPLAY 0.723404 (-3225 1800);
PAINT MONO (-3225 1800);
DISPLAY INVISIBLE (-3225 1800);
FORCEPROP 1 LAST BODY_TYPE PLUMBING
J 0
(-3225 1850);
DISPLAY 0.872340 (-3225 1850);
PAINT GREEN (-3225 1850);
DISPLAY INVISIBLE (-3225 1850);
FORCEPROP 1 LAST HDL_TAP TRUE
J 0
(-2900 1675);
DISPLAY 0.872340 (-2900 1675);
DISPLAY INVISIBLE (-2900 1675);
FORCEPROP 1 LAST PATH I236
J 0
(-3227 1800);
DISPLAY 0.872340 (-3227 1800);
PAINT GREEN (-3227 1800);
DISPLAY INVISIBLE (-3227 1800);
FORCEADD TAP..1
(-3225 1850);
FORCEPROP 3 LASTPIN (-3275 1850) SIG_NAME M_K_CPU1_SB_CB<0>
J 0
(-3265 1860);
DISPLAY 0.659574 (-3265 1860);
PAINT MONO (-3265 1860);
DISPLAY INVISIBLE (-3265 1860);
FORCEPROP 1 LASTPIN (-3275 1850) BN 0
J 0
(-3287 1858);
DISPLAY 0.489362 (-3287 1858);
PAINT GREEN (-3287 1858);
FORCEPROP 2 LAST CDS_LIB mstr_standard
J 2
(-3225 1850);
DISPLAY 0.723404 (-3225 1850);
PAINT MONO (-3225 1850);
DISPLAY INVISIBLE (-3225 1850);
FORCEPROP 1 LAST BODY_TYPE PLUMBING
J 0
(-3225 1900);
DISPLAY 0.872340 (-3225 1900);
PAINT GREEN (-3225 1900);
DISPLAY INVISIBLE (-3225 1900);
FORCEPROP 1 LAST HDL_TAP TRUE
J 0
(-2900 1725);
DISPLAY 0.872340 (-2900 1725);
DISPLAY INVISIBLE (-2900 1725);
FORCEPROP 1 LAST PATH I237
J 0
(-3227 1850);
DISPLAY 0.872340 (-3227 1850);
PAINT GREEN (-3227 1850);
DISPLAY INVISIBLE (-3227 1850);
FORCEADD TAP..1
(-3225 1750);
FORCEPROP 3 LASTPIN (-3275 1750) SIG_NAME M_K_CPU1_SB_CB<2>
J 0
(-3265 1760);
DISPLAY 0.659574 (-3265 1760);
PAINT MONO (-3265 1760);
DISPLAY INVISIBLE (-3265 1760);
FORCEPROP 1 LASTPIN (-3275 1750) BN 2
J 0
(-3287 1758);
DISPLAY 0.489362 (-3287 1758);
PAINT GREEN (-3287 1758);
FORCEPROP 2 LAST CDS_LIB mstr_standard
J 2
(-3225 1750);
DISPLAY 0.723404 (-3225 1750);
PAINT MONO (-3225 1750);
DISPLAY INVISIBLE (-3225 1750);
FORCEPROP 1 LAST BODY_TYPE PLUMBING
J 0
(-3225 1800);
DISPLAY 0.872340 (-3225 1800);
PAINT GREEN (-3225 1800);
DISPLAY INVISIBLE (-3225 1800);
FORCEPROP 1 LAST HDL_TAP TRUE
J 0
(-2900 1625);
DISPLAY 0.872340 (-2900 1625);
DISPLAY INVISIBLE (-2900 1625);
FORCEPROP 1 LAST PATH I238
J 0
(-3227 1750);
DISPLAY 0.872340 (-3227 1750);
PAINT GREEN (-3227 1750);
DISPLAY INVISIBLE (-3227 1750);
FORCEADD TAP..1
(-3225 1700);
FORCEPROP 3 LASTPIN (-3275 1700) SIG_NAME M_K_CPU1_SB_CB<3>
J 0
(-3265 1710);
DISPLAY 0.659574 (-3265 1710);
PAINT MONO (-3265 1710);
DISPLAY INVISIBLE (-3265 1710);
FORCEPROP 1 LASTPIN (-3275 1700) BN 3
J 0
(-3287 1708);
DISPLAY 0.489362 (-3287 1708);
PAINT GREEN (-3287 1708);
FORCEPROP 2 LAST CDS_LIB mstr_standard
J 2
(-3225 1700);
DISPLAY 0.723404 (-3225 1700);
PAINT MONO (-3225 1700);
DISPLAY INVISIBLE (-3225 1700);
FORCEPROP 1 LAST BODY_TYPE PLUMBING
J 0
(-3225 1750);
DISPLAY 0.872340 (-3225 1750);
PAINT GREEN (-3225 1750);
DISPLAY INVISIBLE (-3225 1750);
FORCEPROP 1 LAST HDL_TAP TRUE
J 0
(-2900 1575);
DISPLAY 0.872340 (-2900 1575);
DISPLAY INVISIBLE (-2900 1575);
FORCEPROP 1 LAST PATH I239
J 0
(-3227 1700);
DISPLAY 0.872340 (-3227 1700);
PAINT GREEN (-3227 1700);
DISPLAY INVISIBLE (-3227 1700);
FORCEADD TAP..1
(-3225 1600);
FORCEPROP 3 LASTPIN (-3275 1600) SIG_NAME M_K_CPU1_SB_CB<5>
J 0
(-3265 1610);
DISPLAY 0.659574 (-3265 1610);
PAINT MONO (-3265 1610);
DISPLAY INVISIBLE (-3265 1610);
FORCEPROP 1 LASTPIN (-3275 1600) BN 5
J 0
(-3287 1608);
DISPLAY 0.489362 (-3287 1608);
PAINT GREEN (-3287 1608);
FORCEPROP 2 LAST CDS_LIB mstr_standard
J 2
(-3225 1600);
DISPLAY 0.723404 (-3225 1600);
PAINT MONO (-3225 1600);
DISPLAY INVISIBLE (-3225 1600);
FORCEPROP 1 LAST BODY_TYPE PLUMBING
J 0
(-3225 1650);
DISPLAY 0.872340 (-3225 1650);
PAINT GREEN (-3225 1650);
DISPLAY INVISIBLE (-3225 1650);
FORCEPROP 1 LAST HDL_TAP TRUE
J 0
(-2900 1475);
DISPLAY 0.872340 (-2900 1475);
DISPLAY INVISIBLE (-2900 1475);
FORCEPROP 1 LAST PATH I240
J 0
(-3227 1600);
DISPLAY 0.872340 (-3227 1600);
PAINT GREEN (-3227 1600);
DISPLAY INVISIBLE (-3227 1600);
FORCEADD TAP..1
(-3225 1650);
FORCEPROP 3 LASTPIN (-3275 1650) SIG_NAME M_K_CPU1_SB_CB<4>
J 0
(-3265 1660);
DISPLAY 0.659574 (-3265 1660);
PAINT MONO (-3265 1660);
DISPLAY INVISIBLE (-3265 1660);
FORCEPROP 1 LASTPIN (-3275 1650) BN 4
J 0
(-3287 1658);
DISPLAY 0.489362 (-3287 1658);
PAINT GREEN (-3287 1658);
FORCEPROP 2 LAST CDS_LIB mstr_standard
J 2
(-3225 1650);
DISPLAY 0.723404 (-3225 1650);
PAINT MONO (-3225 1650);
DISPLAY INVISIBLE (-3225 1650);
FORCEPROP 1 LAST BODY_TYPE PLUMBING
J 0
(-3225 1700);
DISPLAY 0.872340 (-3225 1700);
PAINT GREEN (-3225 1700);
DISPLAY INVISIBLE (-3225 1700);
FORCEPROP 1 LAST HDL_TAP TRUE
J 0
(-2900 1525);
DISPLAY 0.872340 (-2900 1525);
DISPLAY INVISIBLE (-2900 1525);
FORCEPROP 1 LAST PATH I241
J 0
(-3227 1650);
DISPLAY 0.872340 (-3227 1650);
PAINT GREEN (-3227 1650);
DISPLAY INVISIBLE (-3227 1650);
FORCEADD TAP..1
(-3225 1550);
FORCEPROP 3 LASTPIN (-3275 1550) SIG_NAME M_K_CPU1_SB_CB<6>
J 0
(-3265 1560);
DISPLAY 0.659574 (-3265 1560);
PAINT MONO (-3265 1560);
DISPLAY INVISIBLE (-3265 1560);
FORCEPROP 1 LASTPIN (-3275 1550) BN 6
J 0
(-3287 1558);
DISPLAY 0.489362 (-3287 1558);
PAINT GREEN (-3287 1558);
FORCEPROP 2 LAST CDS_LIB mstr_standard
J 2
(-3225 1550);
DISPLAY 0.723404 (-3225 1550);
PAINT MONO (-3225 1550);
DISPLAY INVISIBLE (-3225 1550);
FORCEPROP 1 LAST BODY_TYPE PLUMBING
J 0
(-3225 1600);
DISPLAY 0.872340 (-3225 1600);
PAINT GREEN (-3225 1600);
DISPLAY INVISIBLE (-3225 1600);
FORCEPROP 1 LAST HDL_TAP TRUE
J 0
(-2900 1425);
DISPLAY 0.872340 (-2900 1425);
DISPLAY INVISIBLE (-2900 1425);
FORCEPROP 1 LAST PATH I242
J 0
(-3227 1550);
DISPLAY 0.872340 (-3227 1550);
PAINT GREEN (-3227 1550);
DISPLAY INVISIBLE (-3227 1550);
FORCEADD TAP..1
(-3225 1500);
FORCEPROP 3 LASTPIN (-3275 1500) SIG_NAME M_K_CPU1_SB_CB<7>
J 0
(-3265 1510);
DISPLAY 0.659574 (-3265 1510);
PAINT MONO (-3265 1510);
DISPLAY INVISIBLE (-3265 1510);
FORCEPROP 1 LASTPIN (-3275 1500) BN 7
J 0
(-3287 1508);
DISPLAY 0.489362 (-3287 1508);
PAINT GREEN (-3287 1508);
FORCEPROP 2 LAST CDS_LIB mstr_standard
J 2
(-3225 1500);
DISPLAY 0.723404 (-3225 1500);
PAINT MONO (-3225 1500);
DISPLAY INVISIBLE (-3225 1500);
FORCEPROP 1 LAST BODY_TYPE PLUMBING
J 0
(-3225 1550);
DISPLAY 0.872340 (-3225 1550);
PAINT GREEN (-3225 1550);
DISPLAY INVISIBLE (-3225 1550);
FORCEPROP 1 LAST HDL_TAP TRUE
J 0
(-2900 1375);
DISPLAY 0.872340 (-2900 1375);
DISPLAY INVISIBLE (-2900 1375);
FORCEPROP 1 LAST PATH I243
J 0
(-3227 1500);
DISPLAY 0.872340 (-3227 1500);
PAINT GREEN (-3227 1500);
DISPLAY INVISIBLE (-3227 1500);
FORCEADD TAP..1
R 2
(-5650 5900);
FORCEPROP 3 LASTPIN (-5600 5900) SIG_NAME M_K_CPU1_SA_DQS_DP<0>
J 0
(-5590 5910);
DISPLAY 0.659574 (-5590 5910);
PAINT MONO (-5590 5910);
DISPLAY INVISIBLE (-5590 5910);
FORCEPROP 1 LASTPIN (-5600 5900) BN 0
J 2
(-5588 5908);
DISPLAY 0.489362 (-5588 5908);
PAINT GREEN (-5588 5908);
FORCEPROP 2 LAST CDS_LIB mstr_standard
J 2
(-5650 5900);
DISPLAY 0.723404 (-5650 5900);
PAINT MONO (-5650 5900);
DISPLAY INVISIBLE (-5650 5900);
FORCEPROP 1 LAST BODY_TYPE PLUMBING
J 2
(-5650 5950);
DISPLAY 0.872340 (-5650 5950);
PAINT GREEN (-5650 5950);
DISPLAY INVISIBLE (-5650 5950);
FORCEPROP 1 LAST HDL_TAP TRUE
J 2
(-5975 5775);
DISPLAY 0.872340 (-5975 5775);
DISPLAY INVISIBLE (-5975 5775);
FORCEPROP 1 LAST PATH I244
J 2
(-5648 5900);
DISPLAY 0.872340 (-5648 5900);
PAINT GREEN (-5648 5900);
DISPLAY INVISIBLE (-5648 5900);
FORCEADD TAP..1
R 2
(-5650 5800);
FORCEPROP 3 LASTPIN (-5600 5800) SIG_NAME M_K_CPU1_SA_DQS_DP<1>
J 0
(-5590 5810);
DISPLAY 0.659574 (-5590 5810);
PAINT MONO (-5590 5810);
DISPLAY INVISIBLE (-5590 5810);
FORCEPROP 1 LASTPIN (-5600 5800) BN 1
J 2
(-5588 5808);
DISPLAY 0.489362 (-5588 5808);
PAINT GREEN (-5588 5808);
FORCEPROP 2 LAST CDS_LIB mstr_standard
J 2
(-5650 5800);
DISPLAY 0.723404 (-5650 5800);
PAINT MONO (-5650 5800);
DISPLAY INVISIBLE (-5650 5800);
FORCEPROP 1 LAST BODY_TYPE PLUMBING
J 2
(-5650 5850);
DISPLAY 0.872340 (-5650 5850);
PAINT GREEN (-5650 5850);
DISPLAY INVISIBLE (-5650 5850);
FORCEPROP 1 LAST HDL_TAP TRUE
J 2
(-5975 5675);
DISPLAY 0.872340 (-5975 5675);
DISPLAY INVISIBLE (-5975 5675);
FORCEPROP 1 LAST PATH I245
J 2
(-5648 5800);
DISPLAY 0.872340 (-5648 5800);
PAINT GREEN (-5648 5800);
DISPLAY INVISIBLE (-5648 5800);
FORCEADD TAP..1
R 2
(-5650 5700);
FORCEPROP 3 LASTPIN (-5600 5700) SIG_NAME M_K_CPU1_SA_DQS_DP<2>
J 0
(-5590 5710);
DISPLAY 0.659574 (-5590 5710);
PAINT MONO (-5590 5710);
DISPLAY INVISIBLE (-5590 5710);
FORCEPROP 1 LASTPIN (-5600 5700) BN 2
J 2
(-5588 5708);
DISPLAY 0.489362 (-5588 5708);
PAINT GREEN (-5588 5708);
FORCEPROP 2 LAST CDS_LIB mstr_standard
J 2
(-5650 5700);
DISPLAY 0.723404 (-5650 5700);
PAINT MONO (-5650 5700);
DISPLAY INVISIBLE (-5650 5700);
FORCEPROP 1 LAST BODY_TYPE PLUMBING
J 2
(-5650 5750);
DISPLAY 0.872340 (-5650 5750);
PAINT GREEN (-5650 5750);
DISPLAY INVISIBLE (-5650 5750);
FORCEPROP 1 LAST HDL_TAP TRUE
J 2
(-5975 5575);
DISPLAY 0.872340 (-5975 5575);
DISPLAY INVISIBLE (-5975 5575);
FORCEPROP 1 LAST PATH I246
J 2
(-5648 5700);
DISPLAY 0.872340 (-5648 5700);
PAINT GREEN (-5648 5700);
DISPLAY INVISIBLE (-5648 5700);
FORCEADD TAP..1
R 2
(-5650 5600);
FORCEPROP 3 LASTPIN (-5600 5600) SIG_NAME M_K_CPU1_SA_DQS_DP<3>
J 0
(-5590 5610);
DISPLAY 0.659574 (-5590 5610);
PAINT MONO (-5590 5610);
DISPLAY INVISIBLE (-5590 5610);
FORCEPROP 1 LASTPIN (-5600 5600) BN 3
J 2
(-5588 5608);
DISPLAY 0.489362 (-5588 5608);
PAINT GREEN (-5588 5608);
FORCEPROP 2 LAST CDS_LIB mstr_standard
J 2
(-5650 5600);
DISPLAY 0.723404 (-5650 5600);
PAINT MONO (-5650 5600);
DISPLAY INVISIBLE (-5650 5600);
FORCEPROP 1 LAST BODY_TYPE PLUMBING
J 2
(-5650 5650);
DISPLAY 0.872340 (-5650 5650);
PAINT GREEN (-5650 5650);
DISPLAY INVISIBLE (-5650 5650);
FORCEPROP 1 LAST HDL_TAP TRUE
J 2
(-5975 5475);
DISPLAY 0.872340 (-5975 5475);
DISPLAY INVISIBLE (-5975 5475);
FORCEPROP 1 LAST PATH I247
J 2
(-5648 5600);
DISPLAY 0.872340 (-5648 5600);
PAINT GREEN (-5648 5600);
DISPLAY INVISIBLE (-5648 5600);
FORCEADD TAP..1
R 2
(-5650 5400);
FORCEPROP 3 LASTPIN (-5600 5400) SIG_NAME M_K_CPU1_SA_DQS_DP<5>
J 0
(-5590 5410);
DISPLAY 0.659574 (-5590 5410);
PAINT MONO (-5590 5410);
DISPLAY INVISIBLE (-5590 5410);
FORCEPROP 1 LASTPIN (-5600 5400) BN 5
J 2
(-5588 5408);
DISPLAY 0.489362 (-5588 5408);
PAINT GREEN (-5588 5408);
FORCEPROP 2 LAST CDS_LIB mstr_standard
J 2
(-5650 5400);
DISPLAY 0.723404 (-5650 5400);
PAINT MONO (-5650 5400);
DISPLAY INVISIBLE (-5650 5400);
FORCEPROP 1 LAST BODY_TYPE PLUMBING
J 2
(-5650 5450);
DISPLAY 0.872340 (-5650 5450);
PAINT GREEN (-5650 5450);
DISPLAY INVISIBLE (-5650 5450);
FORCEPROP 1 LAST HDL_TAP TRUE
J 2
(-5975 5275);
DISPLAY 0.872340 (-5975 5275);
DISPLAY INVISIBLE (-5975 5275);
FORCEPROP 1 LAST PATH I248
J 2
(-5648 5400);
DISPLAY 0.872340 (-5648 5400);
PAINT GREEN (-5648 5400);
DISPLAY INVISIBLE (-5648 5400);
FORCEADD TAP..1
R 2
(-5650 5500);
FORCEPROP 3 LASTPIN (-5600 5500) SIG_NAME M_K_CPU1_SA_DQS_DP<4>
J 0
(-5590 5510);
DISPLAY 0.659574 (-5590 5510);
PAINT MONO (-5590 5510);
DISPLAY INVISIBLE (-5590 5510);
FORCEPROP 1 LASTPIN (-5600 5500) BN 4
J 2
(-5588 5508);
DISPLAY 0.489362 (-5588 5508);
PAINT GREEN (-5588 5508);
FORCEPROP 2 LAST CDS_LIB mstr_standard
J 2
(-5650 5500);
DISPLAY 0.723404 (-5650 5500);
PAINT MONO (-5650 5500);
DISPLAY INVISIBLE (-5650 5500);
FORCEPROP 1 LAST BODY_TYPE PLUMBING
J 2
(-5650 5550);
DISPLAY 0.872340 (-5650 5550);
PAINT GREEN (-5650 5550);
DISPLAY INVISIBLE (-5650 5550);
FORCEPROP 1 LAST HDL_TAP TRUE
J 2
(-5975 5375);
DISPLAY 0.872340 (-5975 5375);
DISPLAY INVISIBLE (-5975 5375);
FORCEPROP 1 LAST PATH I249
J 2
(-5648 5500);
DISPLAY 0.872340 (-5648 5500);
PAINT GREEN (-5648 5500);
DISPLAY INVISIBLE (-5648 5500);
FORCEADD TAP..1
R 2
(-5650 5300);
FORCEPROP 3 LASTPIN (-5600 5300) SIG_NAME M_K_CPU1_SA_DQS_DP<6>
J 0
(-5590 5310);
DISPLAY 0.659574 (-5590 5310);
PAINT MONO (-5590 5310);
DISPLAY INVISIBLE (-5590 5310);
FORCEPROP 1 LASTPIN (-5600 5300) BN 6
J 2
(-5588 5308);
DISPLAY 0.489362 (-5588 5308);
PAINT GREEN (-5588 5308);
FORCEPROP 2 LAST CDS_LIB mstr_standard
J 2
(-5650 5300);
DISPLAY 0.723404 (-5650 5300);
PAINT MONO (-5650 5300);
DISPLAY INVISIBLE (-5650 5300);
FORCEPROP 1 LAST BODY_TYPE PLUMBING
J 2
(-5650 5350);
DISPLAY 0.872340 (-5650 5350);
PAINT GREEN (-5650 5350);
DISPLAY INVISIBLE (-5650 5350);
FORCEPROP 1 LAST HDL_TAP TRUE
J 2
(-5975 5175);
DISPLAY 0.872340 (-5975 5175);
DISPLAY INVISIBLE (-5975 5175);
FORCEPROP 1 LAST PATH I250
J 2
(-5648 5300);
DISPLAY 0.872340 (-5648 5300);
PAINT GREEN (-5648 5300);
DISPLAY INVISIBLE (-5648 5300);
FORCEADD TAP..1
R 2
(-5650 5200);
FORCEPROP 3 LASTPIN (-5600 5200) SIG_NAME M_K_CPU1_SA_DQS_DP<7>
J 0
(-5590 5210);
DISPLAY 0.659574 (-5590 5210);
PAINT MONO (-5590 5210);
DISPLAY INVISIBLE (-5590 5210);
FORCEPROP 1 LASTPIN (-5600 5200) BN 7
J 2
(-5588 5208);
DISPLAY 0.489362 (-5588 5208);
PAINT GREEN (-5588 5208);
FORCEPROP 2 LAST CDS_LIB mstr_standard
J 2
(-5650 5200);
DISPLAY 0.723404 (-5650 5200);
PAINT MONO (-5650 5200);
DISPLAY INVISIBLE (-5650 5200);
FORCEPROP 1 LAST BODY_TYPE PLUMBING
J 2
(-5650 5250);
DISPLAY 0.872340 (-5650 5250);
PAINT GREEN (-5650 5250);
DISPLAY INVISIBLE (-5650 5250);
FORCEPROP 1 LAST HDL_TAP TRUE
J 2
(-5975 5075);
DISPLAY 0.872340 (-5975 5075);
DISPLAY INVISIBLE (-5975 5075);
FORCEPROP 1 LAST PATH I251
J 2
(-5648 5200);
DISPLAY 0.872340 (-5648 5200);
PAINT GREEN (-5648 5200);
DISPLAY INVISIBLE (-5648 5200);
FORCEADD TAP..1
R 2
(-5850 5750);
FORCEPROP 3 LASTPIN (-5800 5750) SIG_NAME M_K_CPU1_SA_DQS_DN<1>
J 0
(-5790 5760);
DISPLAY 0.659574 (-5790 5760);
PAINT MONO (-5790 5760);
DISPLAY INVISIBLE (-5790 5760);
FORCEPROP 1 LASTPIN (-5800 5750) BN 1
J 2
(-5788 5758);
DISPLAY 0.489362 (-5788 5758);
PAINT GREEN (-5788 5758);
FORCEPROP 2 LAST CDS_LIB mstr_standard
J 2
(-5850 5750);
DISPLAY 0.723404 (-5850 5750);
PAINT MONO (-5850 5750);
DISPLAY INVISIBLE (-5850 5750);
FORCEPROP 1 LAST BODY_TYPE PLUMBING
J 2
(-5850 5800);
DISPLAY 0.872340 (-5850 5800);
PAINT GREEN (-5850 5800);
DISPLAY INVISIBLE (-5850 5800);
FORCEPROP 1 LAST HDL_TAP TRUE
J 2
(-6175 5625);
DISPLAY 0.872340 (-6175 5625);
DISPLAY INVISIBLE (-6175 5625);
FORCEPROP 1 LAST PATH I252
J 2
(-5848 5750);
DISPLAY 0.872340 (-5848 5750);
PAINT GREEN (-5848 5750);
DISPLAY INVISIBLE (-5848 5750);
FORCEADD TAP..1
R 2
(-5850 5850);
FORCEPROP 3 LASTPIN (-5800 5850) SIG_NAME M_K_CPU1_SA_DQS_DN<0>
J 0
(-5790 5860);
DISPLAY 0.659574 (-5790 5860);
PAINT MONO (-5790 5860);
DISPLAY INVISIBLE (-5790 5860);
FORCEPROP 1 LASTPIN (-5800 5850) BN 0
J 2
(-5788 5858);
DISPLAY 0.489362 (-5788 5858);
PAINT GREEN (-5788 5858);
FORCEPROP 2 LAST CDS_LIB mstr_standard
J 2
(-5850 5850);
DISPLAY 0.723404 (-5850 5850);
PAINT MONO (-5850 5850);
DISPLAY INVISIBLE (-5850 5850);
FORCEPROP 1 LAST BODY_TYPE PLUMBING
J 2
(-5850 5900);
DISPLAY 0.872340 (-5850 5900);
PAINT GREEN (-5850 5900);
DISPLAY INVISIBLE (-5850 5900);
FORCEPROP 1 LAST HDL_TAP TRUE
J 2
(-6175 5725);
DISPLAY 0.872340 (-6175 5725);
DISPLAY INVISIBLE (-6175 5725);
FORCEPROP 1 LAST PATH I253
J 2
(-5848 5850);
DISPLAY 0.872340 (-5848 5850);
PAINT GREEN (-5848 5850);
DISPLAY INVISIBLE (-5848 5850);
FORCEADD TAP..1
R 2
(-5850 5650);
FORCEPROP 3 LASTPIN (-5800 5650) SIG_NAME M_K_CPU1_SA_DQS_DN<2>
J 0
(-5790 5660);
DISPLAY 0.659574 (-5790 5660);
PAINT MONO (-5790 5660);
DISPLAY INVISIBLE (-5790 5660);
FORCEPROP 1 LASTPIN (-5800 5650) BN 2
J 2
(-5788 5658);
DISPLAY 0.489362 (-5788 5658);
PAINT GREEN (-5788 5658);
FORCEPROP 2 LAST CDS_LIB mstr_standard
J 2
(-5850 5650);
DISPLAY 0.723404 (-5850 5650);
PAINT MONO (-5850 5650);
DISPLAY INVISIBLE (-5850 5650);
FORCEPROP 1 LAST BODY_TYPE PLUMBING
J 2
(-5850 5700);
DISPLAY 0.872340 (-5850 5700);
PAINT GREEN (-5850 5700);
DISPLAY INVISIBLE (-5850 5700);
FORCEPROP 1 LAST HDL_TAP TRUE
J 2
(-6175 5525);
DISPLAY 0.872340 (-6175 5525);
DISPLAY INVISIBLE (-6175 5525);
FORCEPROP 1 LAST PATH I254
J 2
(-5848 5650);
DISPLAY 0.872340 (-5848 5650);
PAINT GREEN (-5848 5650);
DISPLAY INVISIBLE (-5848 5650);
FORCEADD TAP..1
R 2
(-5850 5550);
FORCEPROP 3 LASTPIN (-5800 5550) SIG_NAME M_K_CPU1_SA_DQS_DN<3>
J 0
(-5790 5560);
DISPLAY 0.659574 (-5790 5560);
PAINT MONO (-5790 5560);
DISPLAY INVISIBLE (-5790 5560);
FORCEPROP 1 LASTPIN (-5800 5550) BN 3
J 2
(-5788 5558);
DISPLAY 0.489362 (-5788 5558);
PAINT GREEN (-5788 5558);
FORCEPROP 2 LAST CDS_LIB mstr_standard
J 2
(-5850 5550);
DISPLAY 0.723404 (-5850 5550);
PAINT MONO (-5850 5550);
DISPLAY INVISIBLE (-5850 5550);
FORCEPROP 1 LAST BODY_TYPE PLUMBING
J 2
(-5850 5600);
DISPLAY 0.872340 (-5850 5600);
PAINT GREEN (-5850 5600);
DISPLAY INVISIBLE (-5850 5600);
FORCEPROP 1 LAST HDL_TAP TRUE
J 2
(-6175 5425);
DISPLAY 0.872340 (-6175 5425);
DISPLAY INVISIBLE (-6175 5425);
FORCEPROP 1 LAST PATH I255
J 2
(-5848 5550);
DISPLAY 0.872340 (-5848 5550);
PAINT GREEN (-5848 5550);
DISPLAY INVISIBLE (-5848 5550);
FORCEADD TAP..1
R 2
(-5850 5450);
FORCEPROP 3 LASTPIN (-5800 5450) SIG_NAME M_K_CPU1_SA_DQS_DN<4>
J 0
(-5790 5460);
DISPLAY 0.659574 (-5790 5460);
PAINT MONO (-5790 5460);
DISPLAY INVISIBLE (-5790 5460);
FORCEPROP 1 LASTPIN (-5800 5450) BN 4
J 2
(-5788 5458);
DISPLAY 0.489362 (-5788 5458);
PAINT GREEN (-5788 5458);
FORCEPROP 2 LAST CDS_LIB mstr_standard
J 2
(-5850 5450);
DISPLAY 0.723404 (-5850 5450);
PAINT MONO (-5850 5450);
DISPLAY INVISIBLE (-5850 5450);
FORCEPROP 1 LAST BODY_TYPE PLUMBING
J 2
(-5850 5500);
DISPLAY 0.872340 (-5850 5500);
PAINT GREEN (-5850 5500);
DISPLAY INVISIBLE (-5850 5500);
FORCEPROP 1 LAST HDL_TAP TRUE
J 2
(-6175 5325);
DISPLAY 0.872340 (-6175 5325);
DISPLAY INVISIBLE (-6175 5325);
FORCEPROP 1 LAST PATH I256
J 2
(-5848 5450);
DISPLAY 0.872340 (-5848 5450);
PAINT GREEN (-5848 5450);
DISPLAY INVISIBLE (-5848 5450);
FORCEADD TAP..1
R 2
(-5850 5350);
FORCEPROP 3 LASTPIN (-5800 5350) SIG_NAME M_K_CPU1_SA_DQS_DN<5>
J 0
(-5790 5360);
DISPLAY 0.659574 (-5790 5360);
PAINT MONO (-5790 5360);
DISPLAY INVISIBLE (-5790 5360);
FORCEPROP 1 LASTPIN (-5800 5350) BN 5
J 2
(-5788 5358);
DISPLAY 0.489362 (-5788 5358);
PAINT GREEN (-5788 5358);
FORCEPROP 2 LAST CDS_LIB mstr_standard
J 2
(-5850 5350);
DISPLAY 0.723404 (-5850 5350);
PAINT MONO (-5850 5350);
DISPLAY INVISIBLE (-5850 5350);
FORCEPROP 1 LAST BODY_TYPE PLUMBING
J 2
(-5850 5400);
DISPLAY 0.872340 (-5850 5400);
PAINT GREEN (-5850 5400);
DISPLAY INVISIBLE (-5850 5400);
FORCEPROP 1 LAST HDL_TAP TRUE
J 2
(-6175 5225);
DISPLAY 0.872340 (-6175 5225);
DISPLAY INVISIBLE (-6175 5225);
FORCEPROP 1 LAST PATH I257
J 2
(-5848 5350);
DISPLAY 0.872340 (-5848 5350);
PAINT GREEN (-5848 5350);
DISPLAY INVISIBLE (-5848 5350);
FORCEADD TAP..1
R 2
(-5850 5250);
FORCEPROP 3 LASTPIN (-5800 5250) SIG_NAME M_K_CPU1_SA_DQS_DN<6>
J 0
(-5790 5260);
DISPLAY 0.659574 (-5790 5260);
PAINT MONO (-5790 5260);
DISPLAY INVISIBLE (-5790 5260);
FORCEPROP 1 LASTPIN (-5800 5250) BN 6
J 2
(-5788 5258);
DISPLAY 0.489362 (-5788 5258);
PAINT GREEN (-5788 5258);
FORCEPROP 2 LAST CDS_LIB mstr_standard
J 2
(-5850 5250);
DISPLAY 0.723404 (-5850 5250);
PAINT MONO (-5850 5250);
DISPLAY INVISIBLE (-5850 5250);
FORCEPROP 1 LAST BODY_TYPE PLUMBING
J 2
(-5850 5300);
DISPLAY 0.872340 (-5850 5300);
PAINT GREEN (-5850 5300);
DISPLAY INVISIBLE (-5850 5300);
FORCEPROP 1 LAST HDL_TAP TRUE
J 2
(-6175 5125);
DISPLAY 0.872340 (-6175 5125);
DISPLAY INVISIBLE (-6175 5125);
FORCEPROP 1 LAST PATH I258
J 2
(-5848 5250);
DISPLAY 0.872340 (-5848 5250);
PAINT GREEN (-5848 5250);
DISPLAY INVISIBLE (-5848 5250);
FORCEADD TAP..1
R 2
(-5850 5150);
FORCEPROP 3 LASTPIN (-5800 5150) SIG_NAME M_K_CPU1_SA_DQS_DN<7>
J 0
(-5790 5160);
DISPLAY 0.659574 (-5790 5160);
PAINT MONO (-5790 5160);
DISPLAY INVISIBLE (-5790 5160);
FORCEPROP 1 LASTPIN (-5800 5150) BN 7
J 2
(-5788 5158);
DISPLAY 0.489362 (-5788 5158);
PAINT GREEN (-5788 5158);
FORCEPROP 2 LAST CDS_LIB mstr_standard
J 2
(-5850 5150);
DISPLAY 0.723404 (-5850 5150);
PAINT MONO (-5850 5150);
DISPLAY INVISIBLE (-5850 5150);
FORCEPROP 1 LAST BODY_TYPE PLUMBING
J 2
(-5850 5200);
DISPLAY 0.872340 (-5850 5200);
PAINT GREEN (-5850 5200);
DISPLAY INVISIBLE (-5850 5200);
FORCEPROP 1 LAST HDL_TAP TRUE
J 2
(-6175 5025);
DISPLAY 0.872340 (-6175 5025);
DISPLAY INVISIBLE (-6175 5025);
FORCEPROP 1 LAST PATH I259
J 2
(-5848 5150);
DISPLAY 0.872340 (-5848 5150);
PAINT GREEN (-5848 5150);
DISPLAY INVISIBLE (-5848 5150);
FORCEADD TAP..1
R 2
(-5650 5100);
FORCEPROP 3 LASTPIN (-5600 5100) SIG_NAME M_K_CPU1_SA_DQS_DP<8>
J 0
(-5590 5110);
DISPLAY 0.659574 (-5590 5110);
PAINT MONO (-5590 5110);
DISPLAY INVISIBLE (-5590 5110);
FORCEPROP 1 LASTPIN (-5600 5100) BN 8
J 2
(-5588 5108);
DISPLAY 0.489362 (-5588 5108);
PAINT GREEN (-5588 5108);
FORCEPROP 2 LAST CDS_LIB mstr_standard
J 2
(-5650 5100);
DISPLAY 0.723404 (-5650 5100);
PAINT MONO (-5650 5100);
DISPLAY INVISIBLE (-5650 5100);
FORCEPROP 1 LAST BODY_TYPE PLUMBING
J 2
(-5650 5150);
DISPLAY 0.872340 (-5650 5150);
PAINT GREEN (-5650 5150);
DISPLAY INVISIBLE (-5650 5150);
FORCEPROP 1 LAST HDL_TAP TRUE
J 2
(-5975 4975);
DISPLAY 0.872340 (-5975 4975);
DISPLAY INVISIBLE (-5975 4975);
FORCEPROP 1 LAST PATH I260
J 2
(-5648 5100);
DISPLAY 0.872340 (-5648 5100);
PAINT GREEN (-5648 5100);
DISPLAY INVISIBLE (-5648 5100);
FORCEADD TAP..1
R 2
(-5650 5000);
FORCEPROP 3 LASTPIN (-5600 5000) SIG_NAME M_K_CPU1_SA_DQS_DP<9>
J 0
(-5590 5010);
DISPLAY 0.659574 (-5590 5010);
PAINT MONO (-5590 5010);
DISPLAY INVISIBLE (-5590 5010);
FORCEPROP 1 LASTPIN (-5600 5000) BN 9
J 2
(-5588 5008);
DISPLAY 0.489362 (-5588 5008);
PAINT GREEN (-5588 5008);
FORCEPROP 2 LAST CDS_LIB mstr_standard
J 2
(-5650 5000);
DISPLAY 0.723404 (-5650 5000);
PAINT MONO (-5650 5000);
DISPLAY INVISIBLE (-5650 5000);
FORCEPROP 1 LAST BODY_TYPE PLUMBING
J 2
(-5650 5050);
DISPLAY 0.872340 (-5650 5050);
PAINT GREEN (-5650 5050);
DISPLAY INVISIBLE (-5650 5050);
FORCEPROP 1 LAST HDL_TAP TRUE
J 2
(-5975 4875);
DISPLAY 0.872340 (-5975 4875);
DISPLAY INVISIBLE (-5975 4875);
FORCEPROP 1 LAST PATH I261
J 2
(-5648 5000);
DISPLAY 0.872340 (-5648 5000);
PAINT GREEN (-5648 5000);
DISPLAY INVISIBLE (-5648 5000);
FORCEADD TAP..1
R 2
(-5650 4850);
FORCEPROP 3 LASTPIN (-5600 4850) SIG_NAME M_K_CPU1_SB_DQS_DP<0>
J 0
(-5590 4860);
DISPLAY 0.659574 (-5590 4860);
PAINT MONO (-5590 4860);
DISPLAY INVISIBLE (-5590 4860);
FORCEPROP 1 LASTPIN (-5600 4850) BN 0
J 2
(-5588 4858);
DISPLAY 0.489362 (-5588 4858);
PAINT GREEN (-5588 4858);
FORCEPROP 2 LAST CDS_LIB mstr_standard
J 2
(-5650 4850);
DISPLAY 0.723404 (-5650 4850);
PAINT MONO (-5650 4850);
DISPLAY INVISIBLE (-5650 4850);
FORCEPROP 1 LAST BODY_TYPE PLUMBING
J 2
(-5650 4900);
DISPLAY 0.872340 (-5650 4900);
PAINT GREEN (-5650 4900);
DISPLAY INVISIBLE (-5650 4900);
FORCEPROP 1 LAST HDL_TAP TRUE
J 2
(-5975 4725);
DISPLAY 0.872340 (-5975 4725);
DISPLAY INVISIBLE (-5975 4725);
FORCEPROP 1 LAST PATH I262
J 2
(-5648 4850);
DISPLAY 0.872340 (-5648 4850);
PAINT GREEN (-5648 4850);
DISPLAY INVISIBLE (-5648 4850);
FORCEADD TAP..1
R 2
(-5650 4750);
FORCEPROP 3 LASTPIN (-5600 4750) SIG_NAME M_K_CPU1_SB_DQS_DP<1>
J 0
(-5590 4760);
DISPLAY 0.659574 (-5590 4760);
PAINT MONO (-5590 4760);
DISPLAY INVISIBLE (-5590 4760);
FORCEPROP 1 LASTPIN (-5600 4750) BN 1
J 2
(-5588 4758);
DISPLAY 0.489362 (-5588 4758);
PAINT GREEN (-5588 4758);
FORCEPROP 2 LAST CDS_LIB mstr_standard
J 2
(-5650 4750);
DISPLAY 0.723404 (-5650 4750);
PAINT MONO (-5650 4750);
DISPLAY INVISIBLE (-5650 4750);
FORCEPROP 1 LAST BODY_TYPE PLUMBING
J 2
(-5650 4800);
DISPLAY 0.872340 (-5650 4800);
PAINT GREEN (-5650 4800);
DISPLAY INVISIBLE (-5650 4800);
FORCEPROP 1 LAST HDL_TAP TRUE
J 2
(-5975 4625);
DISPLAY 0.872340 (-5975 4625);
DISPLAY INVISIBLE (-5975 4625);
FORCEPROP 1 LAST PATH I263
J 2
(-5648 4750);
DISPLAY 0.872340 (-5648 4750);
PAINT GREEN (-5648 4750);
DISPLAY INVISIBLE (-5648 4750);
FORCEADD TAP..1
R 2
(-5650 4650);
FORCEPROP 3 LASTPIN (-5600 4650) SIG_NAME M_K_CPU1_SB_DQS_DP<2>
J 0
(-5590 4660);
DISPLAY 0.659574 (-5590 4660);
PAINT MONO (-5590 4660);
DISPLAY INVISIBLE (-5590 4660);
FORCEPROP 1 LASTPIN (-5600 4650) BN 2
J 2
(-5588 4658);
DISPLAY 0.489362 (-5588 4658);
PAINT GREEN (-5588 4658);
FORCEPROP 2 LAST CDS_LIB mstr_standard
J 2
(-5650 4650);
DISPLAY 0.723404 (-5650 4650);
PAINT MONO (-5650 4650);
DISPLAY INVISIBLE (-5650 4650);
FORCEPROP 1 LAST BODY_TYPE PLUMBING
J 2
(-5650 4700);
DISPLAY 0.872340 (-5650 4700);
PAINT GREEN (-5650 4700);
DISPLAY INVISIBLE (-5650 4700);
FORCEPROP 1 LAST HDL_TAP TRUE
J 2
(-5975 4525);
DISPLAY 0.872340 (-5975 4525);
DISPLAY INVISIBLE (-5975 4525);
FORCEPROP 1 LAST PATH I264
J 2
(-5648 4650);
DISPLAY 0.872340 (-5648 4650);
PAINT GREEN (-5648 4650);
DISPLAY INVISIBLE (-5648 4650);
FORCEADD TAP..1
R 2
(-5650 4550);
FORCEPROP 3 LASTPIN (-5600 4550) SIG_NAME M_K_CPU1_SB_DQS_DP<3>
J 0
(-5590 4560);
DISPLAY 0.659574 (-5590 4560);
PAINT MONO (-5590 4560);
DISPLAY INVISIBLE (-5590 4560);
FORCEPROP 1 LASTPIN (-5600 4550) BN 3
J 2
(-5588 4558);
DISPLAY 0.489362 (-5588 4558);
PAINT GREEN (-5588 4558);
FORCEPROP 2 LAST CDS_LIB mstr_standard
J 2
(-5650 4550);
DISPLAY 0.723404 (-5650 4550);
PAINT MONO (-5650 4550);
DISPLAY INVISIBLE (-5650 4550);
FORCEPROP 1 LAST BODY_TYPE PLUMBING
J 2
(-5650 4600);
DISPLAY 0.872340 (-5650 4600);
PAINT GREEN (-5650 4600);
DISPLAY INVISIBLE (-5650 4600);
FORCEPROP 1 LAST HDL_TAP TRUE
J 2
(-5975 4425);
DISPLAY 0.872340 (-5975 4425);
DISPLAY INVISIBLE (-5975 4425);
FORCEPROP 1 LAST PATH I265
J 2
(-5648 4550);
DISPLAY 0.872340 (-5648 4550);
PAINT GREEN (-5648 4550);
DISPLAY INVISIBLE (-5648 4550);
FORCEADD TAP..1
R 2
(-5650 4450);
FORCEPROP 3 LASTPIN (-5600 4450) SIG_NAME M_K_CPU1_SB_DQS_DP<4>
J 0
(-5590 4460);
DISPLAY 0.659574 (-5590 4460);
PAINT MONO (-5590 4460);
DISPLAY INVISIBLE (-5590 4460);
FORCEPROP 1 LASTPIN (-5600 4450) BN 4
J 2
(-5588 4458);
DISPLAY 0.489362 (-5588 4458);
PAINT GREEN (-5588 4458);
FORCEPROP 2 LAST CDS_LIB mstr_standard
J 2
(-5650 4450);
DISPLAY 0.723404 (-5650 4450);
PAINT MONO (-5650 4450);
DISPLAY INVISIBLE (-5650 4450);
FORCEPROP 1 LAST BODY_TYPE PLUMBING
J 2
(-5650 4500);
DISPLAY 0.872340 (-5650 4500);
PAINT GREEN (-5650 4500);
DISPLAY INVISIBLE (-5650 4500);
FORCEPROP 1 LAST HDL_TAP TRUE
J 2
(-5975 4325);
DISPLAY 0.872340 (-5975 4325);
DISPLAY INVISIBLE (-5975 4325);
FORCEPROP 1 LAST PATH I266
J 2
(-5648 4450);
DISPLAY 0.872340 (-5648 4450);
PAINT GREEN (-5648 4450);
DISPLAY INVISIBLE (-5648 4450);
FORCEADD TAP..1
R 2
(-5650 4250);
FORCEPROP 3 LASTPIN (-5600 4250) SIG_NAME M_K_CPU1_SB_DQS_DP<6>
J 0
(-5590 4260);
DISPLAY 0.659574 (-5590 4260);
PAINT MONO (-5590 4260);
DISPLAY INVISIBLE (-5590 4260);
FORCEPROP 1 LASTPIN (-5600 4250) BN 6
J 2
(-5588 4258);
DISPLAY 0.489362 (-5588 4258);
PAINT GREEN (-5588 4258);
FORCEPROP 2 LAST CDS_LIB mstr_standard
J 2
(-5650 4250);
DISPLAY 0.723404 (-5650 4250);
PAINT MONO (-5650 4250);
DISPLAY INVISIBLE (-5650 4250);
FORCEPROP 1 LAST BODY_TYPE PLUMBING
J 2
(-5650 4300);
DISPLAY 0.872340 (-5650 4300);
PAINT GREEN (-5650 4300);
DISPLAY INVISIBLE (-5650 4300);
FORCEPROP 1 LAST HDL_TAP TRUE
J 2
(-5975 4125);
DISPLAY 0.872340 (-5975 4125);
DISPLAY INVISIBLE (-5975 4125);
FORCEPROP 1 LAST PATH I267
J 2
(-5648 4250);
DISPLAY 0.872340 (-5648 4250);
PAINT GREEN (-5648 4250);
DISPLAY INVISIBLE (-5648 4250);
FORCEADD TAP..1
R 2
(-5650 4350);
FORCEPROP 3 LASTPIN (-5600 4350) SIG_NAME M_K_CPU1_SB_DQS_DP<5>
J 0
(-5590 4360);
DISPLAY 0.659574 (-5590 4360);
PAINT MONO (-5590 4360);
DISPLAY INVISIBLE (-5590 4360);
FORCEPROP 1 LASTPIN (-5600 4350) BN 5
J 2
(-5588 4358);
DISPLAY 0.489362 (-5588 4358);
PAINT GREEN (-5588 4358);
FORCEPROP 2 LAST CDS_LIB mstr_standard
J 2
(-5650 4350);
DISPLAY 0.723404 (-5650 4350);
PAINT MONO (-5650 4350);
DISPLAY INVISIBLE (-5650 4350);
FORCEPROP 1 LAST BODY_TYPE PLUMBING
J 2
(-5650 4400);
DISPLAY 0.872340 (-5650 4400);
PAINT GREEN (-5650 4400);
DISPLAY INVISIBLE (-5650 4400);
FORCEPROP 1 LAST HDL_TAP TRUE
J 2
(-5975 4225);
DISPLAY 0.872340 (-5975 4225);
DISPLAY INVISIBLE (-5975 4225);
FORCEPROP 1 LAST PATH I268
J 2
(-5648 4350);
DISPLAY 0.872340 (-5648 4350);
PAINT GREEN (-5648 4350);
DISPLAY INVISIBLE (-5648 4350);
FORCEADD TAP..1
R 2
(-5650 4150);
FORCEPROP 3 LASTPIN (-5600 4150) SIG_NAME M_K_CPU1_SB_DQS_DP<7>
J 0
(-5590 4160);
DISPLAY 0.659574 (-5590 4160);
PAINT MONO (-5590 4160);
DISPLAY INVISIBLE (-5590 4160);
FORCEPROP 1 LASTPIN (-5600 4150) BN 7
J 2
(-5588 4158);
DISPLAY 0.489362 (-5588 4158);
PAINT GREEN (-5588 4158);
FORCEPROP 2 LAST CDS_LIB mstr_standard
J 2
(-5650 4150);
DISPLAY 0.723404 (-5650 4150);
PAINT MONO (-5650 4150);
DISPLAY INVISIBLE (-5650 4150);
FORCEPROP 1 LAST BODY_TYPE PLUMBING
J 2
(-5650 4200);
DISPLAY 0.872340 (-5650 4200);
PAINT GREEN (-5650 4200);
DISPLAY INVISIBLE (-5650 4200);
FORCEPROP 1 LAST HDL_TAP TRUE
J 2
(-5975 4025);
DISPLAY 0.872340 (-5975 4025);
DISPLAY INVISIBLE (-5975 4025);
FORCEPROP 1 LAST PATH I269
J 2
(-5648 4150);
DISPLAY 0.872340 (-5648 4150);
PAINT GREEN (-5648 4150);
DISPLAY INVISIBLE (-5648 4150);
FORCEADD TAP..1
R 2
(-5850 4950);
FORCEPROP 3 LASTPIN (-5800 4950) SIG_NAME M_K_CPU1_SA_DQS_DN<9>
J 0
(-5790 4960);
DISPLAY 0.659574 (-5790 4960);
PAINT MONO (-5790 4960);
DISPLAY INVISIBLE (-5790 4960);
FORCEPROP 1 LASTPIN (-5800 4950) BN 9
J 2
(-5788 4958);
DISPLAY 0.489362 (-5788 4958);
PAINT GREEN (-5788 4958);
FORCEPROP 2 LAST CDS_LIB mstr_standard
J 2
(-5850 4950);
DISPLAY 0.723404 (-5850 4950);
PAINT MONO (-5850 4950);
DISPLAY INVISIBLE (-5850 4950);
FORCEPROP 1 LAST BODY_TYPE PLUMBING
J 2
(-5850 5000);
DISPLAY 0.872340 (-5850 5000);
PAINT GREEN (-5850 5000);
DISPLAY INVISIBLE (-5850 5000);
FORCEPROP 1 LAST HDL_TAP TRUE
J 2
(-6175 4825);
DISPLAY 0.872340 (-6175 4825);
DISPLAY INVISIBLE (-6175 4825);
FORCEPROP 1 LAST PATH I270
J 2
(-5848 4950);
DISPLAY 0.872340 (-5848 4950);
PAINT GREEN (-5848 4950);
DISPLAY INVISIBLE (-5848 4950);
FORCEADD TAP..1
R 2
(-5850 5050);
FORCEPROP 3 LASTPIN (-5800 5050) SIG_NAME M_K_CPU1_SA_DQS_DN<8>
J 0
(-5790 5060);
DISPLAY 0.659574 (-5790 5060);
PAINT MONO (-5790 5060);
DISPLAY INVISIBLE (-5790 5060);
FORCEPROP 1 LASTPIN (-5800 5050) BN 8
J 2
(-5788 5058);
DISPLAY 0.489362 (-5788 5058);
PAINT GREEN (-5788 5058);
FORCEPROP 2 LAST CDS_LIB mstr_standard
J 2
(-5850 5050);
DISPLAY 0.723404 (-5850 5050);
PAINT MONO (-5850 5050);
DISPLAY INVISIBLE (-5850 5050);
FORCEPROP 1 LAST BODY_TYPE PLUMBING
J 2
(-5850 5100);
DISPLAY 0.872340 (-5850 5100);
PAINT GREEN (-5850 5100);
DISPLAY INVISIBLE (-5850 5100);
FORCEPROP 1 LAST HDL_TAP TRUE
J 2
(-6175 4925);
DISPLAY 0.872340 (-6175 4925);
DISPLAY INVISIBLE (-6175 4925);
FORCEPROP 1 LAST PATH I271
J 2
(-5848 5050);
DISPLAY 0.872340 (-5848 5050);
PAINT GREEN (-5848 5050);
DISPLAY INVISIBLE (-5848 5050);
FORCEADD TAP..1
R 2
(-5850 4800);
FORCEPROP 3 LASTPIN (-5800 4800) SIG_NAME M_K_CPU1_SB_DQS_DN<0>
J 0
(-5790 4810);
DISPLAY 0.659574 (-5790 4810);
PAINT MONO (-5790 4810);
DISPLAY INVISIBLE (-5790 4810);
FORCEPROP 1 LASTPIN (-5800 4800) BN 0
J 2
(-5788 4808);
DISPLAY 0.489362 (-5788 4808);
PAINT GREEN (-5788 4808);
FORCEPROP 2 LAST CDS_LIB mstr_standard
J 2
(-5850 4800);
DISPLAY 0.723404 (-5850 4800);
PAINT MONO (-5850 4800);
DISPLAY INVISIBLE (-5850 4800);
FORCEPROP 1 LAST BODY_TYPE PLUMBING
J 2
(-5850 4850);
DISPLAY 0.872340 (-5850 4850);
PAINT GREEN (-5850 4850);
DISPLAY INVISIBLE (-5850 4850);
FORCEPROP 1 LAST HDL_TAP TRUE
J 2
(-6175 4675);
DISPLAY 0.872340 (-6175 4675);
DISPLAY INVISIBLE (-6175 4675);
FORCEPROP 1 LAST PATH I272
J 2
(-5848 4800);
DISPLAY 0.872340 (-5848 4800);
PAINT GREEN (-5848 4800);
DISPLAY INVISIBLE (-5848 4800);
FORCEADD TAP..1
R 2
(-5850 4700);
FORCEPROP 3 LASTPIN (-5800 4700) SIG_NAME M_K_CPU1_SB_DQS_DN<1>
J 0
(-5790 4710);
DISPLAY 0.659574 (-5790 4710);
PAINT MONO (-5790 4710);
DISPLAY INVISIBLE (-5790 4710);
FORCEPROP 1 LASTPIN (-5800 4700) BN 1
J 2
(-5788 4708);
DISPLAY 0.489362 (-5788 4708);
PAINT GREEN (-5788 4708);
FORCEPROP 2 LAST CDS_LIB mstr_standard
J 2
(-5850 4700);
DISPLAY 0.723404 (-5850 4700);
PAINT MONO (-5850 4700);
DISPLAY INVISIBLE (-5850 4700);
FORCEPROP 1 LAST BODY_TYPE PLUMBING
J 2
(-5850 4750);
DISPLAY 0.872340 (-5850 4750);
PAINT GREEN (-5850 4750);
DISPLAY INVISIBLE (-5850 4750);
FORCEPROP 1 LAST HDL_TAP TRUE
J 2
(-6175 4575);
DISPLAY 0.872340 (-6175 4575);
DISPLAY INVISIBLE (-6175 4575);
FORCEPROP 1 LAST PATH I273
J 2
(-5848 4700);
DISPLAY 0.872340 (-5848 4700);
PAINT GREEN (-5848 4700);
DISPLAY INVISIBLE (-5848 4700);
FORCEADD TAP..1
R 2
(-5850 4600);
FORCEPROP 3 LASTPIN (-5800 4600) SIG_NAME M_K_CPU1_SB_DQS_DN<2>
J 0
(-5790 4610);
DISPLAY 0.659574 (-5790 4610);
PAINT MONO (-5790 4610);
DISPLAY INVISIBLE (-5790 4610);
FORCEPROP 1 LASTPIN (-5800 4600) BN 2
J 2
(-5788 4608);
DISPLAY 0.489362 (-5788 4608);
PAINT GREEN (-5788 4608);
FORCEPROP 2 LAST CDS_LIB mstr_standard
J 2
(-5850 4600);
DISPLAY 0.723404 (-5850 4600);
PAINT MONO (-5850 4600);
DISPLAY INVISIBLE (-5850 4600);
FORCEPROP 1 LAST BODY_TYPE PLUMBING
J 2
(-5850 4650);
DISPLAY 0.872340 (-5850 4650);
PAINT GREEN (-5850 4650);
DISPLAY INVISIBLE (-5850 4650);
FORCEPROP 1 LAST HDL_TAP TRUE
J 2
(-6175 4475);
DISPLAY 0.872340 (-6175 4475);
DISPLAY INVISIBLE (-6175 4475);
FORCEPROP 1 LAST PATH I274
J 2
(-5848 4600);
DISPLAY 0.872340 (-5848 4600);
PAINT GREEN (-5848 4600);
DISPLAY INVISIBLE (-5848 4600);
FORCEADD TAP..1
R 2
(-5850 4500);
FORCEPROP 3 LASTPIN (-5800 4500) SIG_NAME M_K_CPU1_SB_DQS_DN<3>
J 0
(-5790 4510);
DISPLAY 0.659574 (-5790 4510);
PAINT MONO (-5790 4510);
DISPLAY INVISIBLE (-5790 4510);
FORCEPROP 1 LASTPIN (-5800 4500) BN 3
J 2
(-5788 4508);
DISPLAY 0.489362 (-5788 4508);
PAINT GREEN (-5788 4508);
FORCEPROP 2 LAST CDS_LIB mstr_standard
J 2
(-5850 4500);
DISPLAY 0.723404 (-5850 4500);
PAINT MONO (-5850 4500);
DISPLAY INVISIBLE (-5850 4500);
FORCEPROP 1 LAST BODY_TYPE PLUMBING
J 2
(-5850 4550);
DISPLAY 0.872340 (-5850 4550);
PAINT GREEN (-5850 4550);
DISPLAY INVISIBLE (-5850 4550);
FORCEPROP 1 LAST HDL_TAP TRUE
J 2
(-6175 4375);
DISPLAY 0.872340 (-6175 4375);
DISPLAY INVISIBLE (-6175 4375);
FORCEPROP 1 LAST PATH I275
J 2
(-5848 4500);
DISPLAY 0.872340 (-5848 4500);
PAINT GREEN (-5848 4500);
DISPLAY INVISIBLE (-5848 4500);
FORCEADD TAP..1
R 2
(-5850 4400);
FORCEPROP 3 LASTPIN (-5800 4400) SIG_NAME M_K_CPU1_SB_DQS_DN<4>
J 0
(-5790 4410);
DISPLAY 0.659574 (-5790 4410);
PAINT MONO (-5790 4410);
DISPLAY INVISIBLE (-5790 4410);
FORCEPROP 1 LASTPIN (-5800 4400) BN 4
J 2
(-5788 4408);
DISPLAY 0.489362 (-5788 4408);
PAINT GREEN (-5788 4408);
FORCEPROP 2 LAST CDS_LIB mstr_standard
J 2
(-5850 4400);
DISPLAY 0.723404 (-5850 4400);
PAINT MONO (-5850 4400);
DISPLAY INVISIBLE (-5850 4400);
FORCEPROP 1 LAST BODY_TYPE PLUMBING
J 2
(-5850 4450);
DISPLAY 0.872340 (-5850 4450);
PAINT GREEN (-5850 4450);
DISPLAY INVISIBLE (-5850 4450);
FORCEPROP 1 LAST HDL_TAP TRUE
J 2
(-6175 4275);
DISPLAY 0.872340 (-6175 4275);
DISPLAY INVISIBLE (-6175 4275);
FORCEPROP 1 LAST PATH I276
J 2
(-5848 4400);
DISPLAY 0.872340 (-5848 4400);
PAINT GREEN (-5848 4400);
DISPLAY INVISIBLE (-5848 4400);
FORCEADD TAP..1
R 2
(-5850 4200);
FORCEPROP 3 LASTPIN (-5800 4200) SIG_NAME M_K_CPU1_SB_DQS_DN<6>
J 0
(-5790 4210);
DISPLAY 0.659574 (-5790 4210);
PAINT MONO (-5790 4210);
DISPLAY INVISIBLE (-5790 4210);
FORCEPROP 1 LASTPIN (-5800 4200) BN 6
J 2
(-5788 4208);
DISPLAY 0.489362 (-5788 4208);
PAINT GREEN (-5788 4208);
FORCEPROP 2 LAST CDS_LIB mstr_standard
J 2
(-5850 4200);
DISPLAY 0.723404 (-5850 4200);
PAINT MONO (-5850 4200);
DISPLAY INVISIBLE (-5850 4200);
FORCEPROP 1 LAST BODY_TYPE PLUMBING
J 2
(-5850 4250);
DISPLAY 0.872340 (-5850 4250);
PAINT GREEN (-5850 4250);
DISPLAY INVISIBLE (-5850 4250);
FORCEPROP 1 LAST HDL_TAP TRUE
J 2
(-6175 4075);
DISPLAY 0.872340 (-6175 4075);
DISPLAY INVISIBLE (-6175 4075);
FORCEPROP 1 LAST PATH I277
J 2
(-5848 4200);
DISPLAY 0.872340 (-5848 4200);
PAINT GREEN (-5848 4200);
DISPLAY INVISIBLE (-5848 4200);
FORCEADD TAP..1
R 2
(-5850 4300);
FORCEPROP 3 LASTPIN (-5800 4300) SIG_NAME M_K_CPU1_SB_DQS_DN<5>
J 0
(-5790 4310);
DISPLAY 0.659574 (-5790 4310);
PAINT MONO (-5790 4310);
DISPLAY INVISIBLE (-5790 4310);
FORCEPROP 1 LASTPIN (-5800 4300) BN 5
J 2
(-5788 4308);
DISPLAY 0.489362 (-5788 4308);
PAINT GREEN (-5788 4308);
FORCEPROP 2 LAST CDS_LIB mstr_standard
J 2
(-5850 4300);
DISPLAY 0.723404 (-5850 4300);
PAINT MONO (-5850 4300);
DISPLAY INVISIBLE (-5850 4300);
FORCEPROP 1 LAST BODY_TYPE PLUMBING
J 2
(-5850 4350);
DISPLAY 0.872340 (-5850 4350);
PAINT GREEN (-5850 4350);
DISPLAY INVISIBLE (-5850 4350);
FORCEPROP 1 LAST HDL_TAP TRUE
J 2
(-6175 4175);
DISPLAY 0.872340 (-6175 4175);
DISPLAY INVISIBLE (-6175 4175);
FORCEPROP 1 LAST PATH I278
J 2
(-5848 4300);
DISPLAY 0.872340 (-5848 4300);
PAINT GREEN (-5848 4300);
DISPLAY INVISIBLE (-5848 4300);
FORCEADD TAP..1
R 2
(-5850 4100);
FORCEPROP 3 LASTPIN (-5800 4100) SIG_NAME M_K_CPU1_SB_DQS_DN<7>
J 0
(-5790 4110);
DISPLAY 0.659574 (-5790 4110);
PAINT MONO (-5790 4110);
DISPLAY INVISIBLE (-5790 4110);
FORCEPROP 1 LASTPIN (-5800 4100) BN 7
J 2
(-5788 4108);
DISPLAY 0.489362 (-5788 4108);
PAINT GREEN (-5788 4108);
FORCEPROP 2 LAST CDS_LIB mstr_standard
J 2
(-5850 4100);
DISPLAY 0.723404 (-5850 4100);
PAINT MONO (-5850 4100);
DISPLAY INVISIBLE (-5850 4100);
FORCEPROP 1 LAST BODY_TYPE PLUMBING
J 2
(-5850 4150);
DISPLAY 0.872340 (-5850 4150);
PAINT GREEN (-5850 4150);
DISPLAY INVISIBLE (-5850 4150);
FORCEPROP 1 LAST HDL_TAP TRUE
J 2
(-6175 3975);
DISPLAY 0.872340 (-6175 3975);
DISPLAY INVISIBLE (-6175 3975);
FORCEPROP 1 LAST PATH I279
J 2
(-5848 4100);
DISPLAY 0.872340 (-5848 4100);
PAINT GREEN (-5848 4100);
DISPLAY INVISIBLE (-5848 4100);
FORCEADD OFFPAGE..3
R 2
(-6550 5925);
FORCEPROP 2 LAST $XR0 107 
J 0
(-6830 5925);
DISPLAY 0.638298 (-6830 5925);
PAINT MONO (-6830 5925);
FORCEPROP 2 LAST PATH I280
J 0
(-6825 5975);
DISPLAY 1.021277 (-6825 5975);
DISPLAY INVISIBLE (-6825 5975);
FORCEPROP 1 LAST COMMENT_BODY TRUE
J 2
(-6500 5825);
DISPLAY 0.872340 (-6500 5825);
PAINT GREEN (-6500 5825);
DISPLAY INVISIBLE (-6500 5825);
FORCEPROP 1 LAST OFFPAGE TRUE
J 2
(-6875 5800);
DISPLAY 0.872340 (-6875 5800);
PAINT GREEN (-6875 5800);
DISPLAY INVISIBLE (-6875 5800);
FORCEPROP 2 LAST CDS_LIB standard
J 0
(-6550 5925);
DISPLAY INVISIBLE (-6550 5925);
FORCEADD OFFPAGE..3
R 2
(-6550 5875);
FORCEPROP 2 LAST $XR0 107 
J 0
(-6830 5875);
DISPLAY 0.638298 (-6830 5875);
PAINT MONO (-6830 5875);
FORCEPROP 2 LAST PATH I281
J 0
(-6825 5925);
DISPLAY 1.021277 (-6825 5925);
DISPLAY INVISIBLE (-6825 5925);
FORCEPROP 1 LAST COMMENT_BODY TRUE
J 2
(-6500 5775);
DISPLAY 0.872340 (-6500 5775);
PAINT GREEN (-6500 5775);
DISPLAY INVISIBLE (-6500 5775);
FORCEPROP 1 LAST OFFPAGE TRUE
J 2
(-6875 5750);
DISPLAY 0.872340 (-6875 5750);
PAINT GREEN (-6875 5750);
DISPLAY INVISIBLE (-6875 5750);
FORCEPROP 2 LAST CDS_LIB standard
J 0
(-6550 5875);
DISPLAY INVISIBLE (-6550 5875);
FORCEADD OFFPAGE..3
R 2
(-6550 4875);
FORCEPROP 2 LAST $XR0 107 
J 0
(-6830 4875);
DISPLAY 0.638298 (-6830 4875);
PAINT MONO (-6830 4875);
FORCEPROP 2 LAST PATH I282
J 0
(-6825 4925);
DISPLAY 1.021277 (-6825 4925);
DISPLAY INVISIBLE (-6825 4925);
FORCEPROP 1 LAST COMMENT_BODY TRUE
J 2
(-6500 4775);
DISPLAY 0.872340 (-6500 4775);
PAINT GREEN (-6500 4775);
DISPLAY INVISIBLE (-6500 4775);
FORCEPROP 1 LAST OFFPAGE TRUE
J 2
(-6875 4750);
DISPLAY 0.872340 (-6875 4750);
PAINT GREEN (-6875 4750);
DISPLAY INVISIBLE (-6875 4750);
FORCEPROP 2 LAST CDS_LIB standard
J 0
(-6550 4875);
DISPLAY INVISIBLE (-6550 4875);
FORCEADD OFFPAGE..3
R 2
(-6550 4825);
FORCEPROP 2 LAST $XR0 107 
J 0
(-6830 4825);
DISPLAY 0.638298 (-6830 4825);
PAINT MONO (-6830 4825);
FORCEPROP 2 LAST PATH I283
J 0
(-6825 4875);
DISPLAY 1.021277 (-6825 4875);
DISPLAY INVISIBLE (-6825 4875);
FORCEPROP 1 LAST COMMENT_BODY TRUE
J 2
(-6500 4725);
DISPLAY 0.872340 (-6500 4725);
PAINT GREEN (-6500 4725);
DISPLAY INVISIBLE (-6500 4725);
FORCEPROP 1 LAST OFFPAGE TRUE
J 2
(-6875 4700);
DISPLAY 0.872340 (-6875 4700);
PAINT GREEN (-6875 4700);
DISPLAY INVISIBLE (-6875 4700);
FORCEPROP 2 LAST CDS_LIB standard
J 0
(-6550 4825);
DISPLAY INVISIBLE (-6550 4825);
FORCEADD TAP..1
R 2
(-5650 3950);
FORCEPROP 3 LASTPIN (-5600 3950) SIG_NAME M_K_CPU1_SB_DQS_DP<9>
J 0
(-5590 3960);
DISPLAY 0.659574 (-5590 3960);
PAINT MONO (-5590 3960);
DISPLAY INVISIBLE (-5590 3960);
FORCEPROP 1 LASTPIN (-5600 3950) BN 9
J 2
(-5588 3958);
DISPLAY 0.489362 (-5588 3958);
PAINT GREEN (-5588 3958);
FORCEPROP 2 LAST CDS_LIB mstr_standard
J 2
(-5650 3950);
DISPLAY 0.723404 (-5650 3950);
PAINT MONO (-5650 3950);
DISPLAY INVISIBLE (-5650 3950);
FORCEPROP 1 LAST BODY_TYPE PLUMBING
J 2
(-5650 4000);
DISPLAY 0.872340 (-5650 4000);
PAINT GREEN (-5650 4000);
DISPLAY INVISIBLE (-5650 4000);
FORCEPROP 1 LAST HDL_TAP TRUE
J 2
(-5975 3825);
DISPLAY 0.872340 (-5975 3825);
DISPLAY INVISIBLE (-5975 3825);
FORCEPROP 1 LAST PATH I284
J 2
(-5648 3950);
DISPLAY 0.872340 (-5648 3950);
PAINT GREEN (-5648 3950);
DISPLAY INVISIBLE (-5648 3950);
FORCEADD TAP..1
R 2
(-5650 4050);
FORCEPROP 3 LASTPIN (-5600 4050) SIG_NAME M_K_CPU1_SB_DQS_DP<8>
J 0
(-5590 4060);
DISPLAY 0.659574 (-5590 4060);
PAINT MONO (-5590 4060);
DISPLAY INVISIBLE (-5590 4060);
FORCEPROP 1 LASTPIN (-5600 4050) BN 8
J 2
(-5588 4058);
DISPLAY 0.489362 (-5588 4058);
PAINT GREEN (-5588 4058);
FORCEPROP 2 LAST CDS_LIB mstr_standard
J 2
(-5650 4050);
DISPLAY 0.723404 (-5650 4050);
PAINT MONO (-5650 4050);
DISPLAY INVISIBLE (-5650 4050);
FORCEPROP 1 LAST BODY_TYPE PLUMBING
J 2
(-5650 4100);
DISPLAY 0.872340 (-5650 4100);
PAINT GREEN (-5650 4100);
DISPLAY INVISIBLE (-5650 4100);
FORCEPROP 1 LAST HDL_TAP TRUE
J 2
(-5975 3925);
DISPLAY 0.872340 (-5975 3925);
DISPLAY INVISIBLE (-5975 3925);
FORCEPROP 1 LAST PATH I285
J 2
(-5648 4050);
DISPLAY 0.872340 (-5648 4050);
PAINT GREEN (-5648 4050);
DISPLAY INVISIBLE (-5648 4050);
FORCEADD TAP..1
R 2
(-5850 4000);
FORCEPROP 3 LASTPIN (-5800 4000) SIG_NAME M_K_CPU1_SB_DQS_DN<8>
J 0
(-5790 4010);
DISPLAY 0.659574 (-5790 4010);
PAINT MONO (-5790 4010);
DISPLAY INVISIBLE (-5790 4010);
FORCEPROP 1 LASTPIN (-5800 4000) BN 8
J 2
(-5788 4008);
DISPLAY 0.489362 (-5788 4008);
PAINT GREEN (-5788 4008);
FORCEPROP 2 LAST CDS_LIB mstr_standard
J 2
(-5850 4000);
DISPLAY 0.723404 (-5850 4000);
PAINT MONO (-5850 4000);
DISPLAY INVISIBLE (-5850 4000);
FORCEPROP 1 LAST BODY_TYPE PLUMBING
J 2
(-5850 4050);
DISPLAY 0.872340 (-5850 4050);
PAINT GREEN (-5850 4050);
DISPLAY INVISIBLE (-5850 4050);
FORCEPROP 1 LAST HDL_TAP TRUE
J 2
(-6175 3875);
DISPLAY 0.872340 (-6175 3875);
DISPLAY INVISIBLE (-6175 3875);
FORCEPROP 1 LAST PATH I286
J 2
(-5848 4000);
DISPLAY 0.872340 (-5848 4000);
PAINT GREEN (-5848 4000);
DISPLAY INVISIBLE (-5848 4000);
FORCEADD TAP..1
R 2
(-5850 3900);
FORCEPROP 3 LASTPIN (-5800 3900) SIG_NAME M_K_CPU1_SB_DQS_DN<9>
J 0
(-5790 3910);
DISPLAY 0.659574 (-5790 3910);
PAINT MONO (-5790 3910);
DISPLAY INVISIBLE (-5790 3910);
FORCEPROP 1 LASTPIN (-5800 3900) BN 9
J 2
(-5788 3908);
DISPLAY 0.489362 (-5788 3908);
PAINT GREEN (-5788 3908);
FORCEPROP 2 LAST CDS_LIB mstr_standard
J 2
(-5850 3900);
DISPLAY 0.723404 (-5850 3900);
PAINT MONO (-5850 3900);
DISPLAY INVISIBLE (-5850 3900);
FORCEPROP 1 LAST BODY_TYPE PLUMBING
J 2
(-5850 3950);
DISPLAY 0.872340 (-5850 3950);
PAINT GREEN (-5850 3950);
DISPLAY INVISIBLE (-5850 3950);
FORCEPROP 1 LAST HDL_TAP TRUE
J 2
(-6175 3775);
DISPLAY 0.872340 (-6175 3775);
DISPLAY INVISIBLE (-6175 3775);
FORCEPROP 1 LAST PATH I287
J 2
(-5848 3900);
DISPLAY 0.872340 (-5848 3900);
PAINT GREEN (-5848 3900);
DISPLAY INVISIBLE (-5848 3900);
FORCEADD TAP..1
R 2
(-5850 3600);
FORCEPROP 3 LASTPIN (-5800 3600) SIG_NAME M_K_CPU1_SA_CA<3>
J 0
(-5790 3610);
DISPLAY 0.659574 (-5790 3610);
PAINT MONO (-5790 3610);
DISPLAY INVISIBLE (-5790 3610);
FORCEPROP 1 LASTPIN (-5800 3600) BN 3
J 2
(-5788 3608);
DISPLAY 0.489362 (-5788 3608);
PAINT GREEN (-5788 3608);
FORCEPROP 2 LAST CDS_LIB mstr_standard
J 0
(-5850 3600);
DISPLAY 0.723404 (-5850 3600);
PAINT MONO (-5850 3600);
DISPLAY INVISIBLE (-5850 3600);
FORCEPROP 1 LAST BODY_TYPE PLUMBING
J 2
(-5850 3650);
DISPLAY 0.872340 (-5850 3650);
PAINT GREEN (-5850 3650);
DISPLAY INVISIBLE (-5850 3650);
FORCEPROP 1 LAST HDL_TAP TRUE
J 2
(-6175 3475);
DISPLAY 0.872340 (-6175 3475);
DISPLAY INVISIBLE (-6175 3475);
FORCEPROP 1 LAST PATH I288
J 2
(-5848 3600);
DISPLAY 0.872340 (-5848 3600);
PAINT GREEN (-5848 3600);
DISPLAY INVISIBLE (-5848 3600);
FORCEADD TAP..1
R 2
(-5850 3750);
FORCEPROP 3 LASTPIN (-5800 3750) SIG_NAME M_K_CPU1_SA_CA<0>
J 0
(-5790 3760);
DISPLAY 0.659574 (-5790 3760);
PAINT MONO (-5790 3760);
DISPLAY INVISIBLE (-5790 3760);
FORCEPROP 1 LASTPIN (-5800 3750) BN 0
J 2
(-5788 3758);
DISPLAY 0.489362 (-5788 3758);
PAINT GREEN (-5788 3758);
FORCEPROP 2 LAST CDS_LIB mstr_standard
J 0
(-5850 3750);
DISPLAY 0.723404 (-5850 3750);
PAINT MONO (-5850 3750);
DISPLAY INVISIBLE (-5850 3750);
FORCEPROP 1 LAST BODY_TYPE PLUMBING
J 2
(-5850 3800);
DISPLAY 0.872340 (-5850 3800);
PAINT GREEN (-5850 3800);
DISPLAY INVISIBLE (-5850 3800);
FORCEPROP 1 LAST HDL_TAP TRUE
J 2
(-6175 3625);
DISPLAY 0.872340 (-6175 3625);
DISPLAY INVISIBLE (-6175 3625);
FORCEPROP 1 LAST PATH I289
J 2
(-5848 3750);
DISPLAY 0.872340 (-5848 3750);
PAINT GREEN (-5848 3750);
DISPLAY INVISIBLE (-5848 3750);
FORCEADD TAP..1
R 2
(-5850 3700);
FORCEPROP 3 LASTPIN (-5800 3700) SIG_NAME M_K_CPU1_SA_CA<1>
J 0
(-5790 3710);
DISPLAY 0.659574 (-5790 3710);
PAINT MONO (-5790 3710);
DISPLAY INVISIBLE (-5790 3710);
FORCEPROP 1 LASTPIN (-5800 3700) BN 1
J 2
(-5788 3708);
DISPLAY 0.489362 (-5788 3708);
PAINT GREEN (-5788 3708);
FORCEPROP 2 LAST CDS_LIB mstr_standard
J 0
(-5850 3700);
DISPLAY 0.723404 (-5850 3700);
PAINT MONO (-5850 3700);
DISPLAY INVISIBLE (-5850 3700);
FORCEPROP 1 LAST BODY_TYPE PLUMBING
J 2
(-5850 3750);
DISPLAY 0.872340 (-5850 3750);
PAINT GREEN (-5850 3750);
DISPLAY INVISIBLE (-5850 3750);
FORCEPROP 1 LAST HDL_TAP TRUE
J 2
(-6175 3575);
DISPLAY 0.872340 (-6175 3575);
DISPLAY INVISIBLE (-6175 3575);
FORCEPROP 1 LAST PATH I290
J 2
(-5848 3700);
DISPLAY 0.872340 (-5848 3700);
PAINT GREEN (-5848 3700);
DISPLAY INVISIBLE (-5848 3700);
FORCEADD TAP..1
R 2
(-5850 3650);
FORCEPROP 3 LASTPIN (-5800 3650) SIG_NAME M_K_CPU1_SA_CA<2>
J 0
(-5790 3660);
DISPLAY 0.659574 (-5790 3660);
PAINT MONO (-5790 3660);
DISPLAY INVISIBLE (-5790 3660);
FORCEPROP 1 LASTPIN (-5800 3650) BN 2
J 2
(-5788 3658);
DISPLAY 0.489362 (-5788 3658);
PAINT GREEN (-5788 3658);
FORCEPROP 2 LAST CDS_LIB mstr_standard
J 0
(-5850 3650);
DISPLAY 0.723404 (-5850 3650);
PAINT MONO (-5850 3650);
DISPLAY INVISIBLE (-5850 3650);
FORCEPROP 1 LAST BODY_TYPE PLUMBING
J 2
(-5850 3700);
DISPLAY 0.872340 (-5850 3700);
PAINT GREEN (-5850 3700);
DISPLAY INVISIBLE (-5850 3700);
FORCEPROP 1 LAST HDL_TAP TRUE
J 2
(-6175 3525);
DISPLAY 0.872340 (-6175 3525);
DISPLAY INVISIBLE (-6175 3525);
FORCEPROP 1 LAST PATH I291
J 2
(-5848 3650);
DISPLAY 0.872340 (-5848 3650);
PAINT GREEN (-5848 3650);
DISPLAY INVISIBLE (-5848 3650);
FORCEADD TAP..1
R 2
(-5850 3350);
FORCEPROP 3 LASTPIN (-5800 3350) SIG_NAME M_K_CPU1_SB_CA<0>
J 0
(-5790 3360);
DISPLAY 0.659574 (-5790 3360);
PAINT MONO (-5790 3360);
DISPLAY INVISIBLE (-5790 3360);
FORCEPROP 1 LASTPIN (-5800 3350) BN 0
J 2
(-5788 3358);
DISPLAY 0.489362 (-5788 3358);
PAINT GREEN (-5788 3358);
FORCEPROP 2 LAST CDS_LIB mstr_standard
J 0
(-5850 3350);
DISPLAY 0.723404 (-5850 3350);
PAINT MONO (-5850 3350);
DISPLAY INVISIBLE (-5850 3350);
FORCEPROP 1 LAST BODY_TYPE PLUMBING
J 2
(-5850 3400);
DISPLAY 0.872340 (-5850 3400);
PAINT GREEN (-5850 3400);
DISPLAY INVISIBLE (-5850 3400);
FORCEPROP 1 LAST HDL_TAP TRUE
J 2
(-6175 3225);
DISPLAY 0.872340 (-6175 3225);
DISPLAY INVISIBLE (-6175 3225);
FORCEPROP 1 LAST PATH I292
J 2
(-5848 3350);
DISPLAY 0.872340 (-5848 3350);
PAINT GREEN (-5848 3350);
DISPLAY INVISIBLE (-5848 3350);
FORCEADD TAP..1
R 2
(-5850 3550);
FORCEPROP 3 LASTPIN (-5800 3550) SIG_NAME M_K_CPU1_SA_CA<4>
J 0
(-5790 3560);
DISPLAY 0.659574 (-5790 3560);
PAINT MONO (-5790 3560);
DISPLAY INVISIBLE (-5790 3560);
FORCEPROP 1 LASTPIN (-5800 3550) BN 4
J 2
(-5788 3558);
DISPLAY 0.489362 (-5788 3558);
PAINT GREEN (-5788 3558);
FORCEPROP 2 LAST CDS_LIB mstr_standard
J 0
(-5850 3550);
DISPLAY 0.723404 (-5850 3550);
PAINT MONO (-5850 3550);
DISPLAY INVISIBLE (-5850 3550);
FORCEPROP 1 LAST BODY_TYPE PLUMBING
J 2
(-5850 3600);
DISPLAY 0.872340 (-5850 3600);
PAINT GREEN (-5850 3600);
DISPLAY INVISIBLE (-5850 3600);
FORCEPROP 1 LAST HDL_TAP TRUE
J 2
(-6175 3425);
DISPLAY 0.872340 (-6175 3425);
DISPLAY INVISIBLE (-6175 3425);
FORCEPROP 1 LAST PATH I293
J 2
(-5848 3550);
DISPLAY 0.872340 (-5848 3550);
PAINT GREEN (-5848 3550);
DISPLAY INVISIBLE (-5848 3550);
FORCEADD TAP..1
R 2
(-5850 3450);
FORCEPROP 3 LASTPIN (-5800 3450) SIG_NAME M_K_CPU1_SA_CA<6>
J 0
(-5790 3460);
DISPLAY 0.659574 (-5790 3460);
PAINT MONO (-5790 3460);
DISPLAY INVISIBLE (-5790 3460);
FORCEPROP 1 LASTPIN (-5800 3450) BN 6
J 2
(-5788 3458);
DISPLAY 0.489362 (-5788 3458);
PAINT GREEN (-5788 3458);
FORCEPROP 2 LAST CDS_LIB mstr_standard
J 0
(-5850 3450);
DISPLAY 0.723404 (-5850 3450);
PAINT MONO (-5850 3450);
DISPLAY INVISIBLE (-5850 3450);
FORCEPROP 1 LAST BODY_TYPE PLUMBING
J 2
(-5850 3500);
DISPLAY 0.872340 (-5850 3500);
PAINT GREEN (-5850 3500);
DISPLAY INVISIBLE (-5850 3500);
FORCEPROP 1 LAST HDL_TAP TRUE
J 2
(-6175 3325);
DISPLAY 0.872340 (-6175 3325);
DISPLAY INVISIBLE (-6175 3325);
FORCEPROP 1 LAST PATH I294
J 2
(-5848 3450);
DISPLAY 0.872340 (-5848 3450);
PAINT GREEN (-5848 3450);
DISPLAY INVISIBLE (-5848 3450);
FORCEADD TAP..1
R 2
(-5850 3500);
FORCEPROP 3 LASTPIN (-5800 3500) SIG_NAME M_K_CPU1_SA_CA<5>
J 0
(-5790 3510);
DISPLAY 0.659574 (-5790 3510);
PAINT MONO (-5790 3510);
DISPLAY INVISIBLE (-5790 3510);
FORCEPROP 1 LASTPIN (-5800 3500) BN 5
J 2
(-5788 3508);
DISPLAY 0.489362 (-5788 3508);
PAINT GREEN (-5788 3508);
FORCEPROP 2 LAST CDS_LIB mstr_standard
J 0
(-5850 3500);
DISPLAY 0.723404 (-5850 3500);
PAINT MONO (-5850 3500);
DISPLAY INVISIBLE (-5850 3500);
FORCEPROP 1 LAST BODY_TYPE PLUMBING
J 2
(-5850 3550);
DISPLAY 0.872340 (-5850 3550);
PAINT GREEN (-5850 3550);
DISPLAY INVISIBLE (-5850 3550);
FORCEPROP 1 LAST HDL_TAP TRUE
J 2
(-6175 3375);
DISPLAY 0.872340 (-6175 3375);
DISPLAY INVISIBLE (-6175 3375);
FORCEPROP 1 LAST PATH I295
J 2
(-5848 3500);
DISPLAY 0.872340 (-5848 3500);
PAINT GREEN (-5848 3500);
DISPLAY INVISIBLE (-5848 3500);
FORCEADD TAP..1
R 2
(-5850 3250);
FORCEPROP 3 LASTPIN (-5800 3250) SIG_NAME M_K_CPU1_SB_CA<2>
J 0
(-5790 3260);
DISPLAY 0.659574 (-5790 3260);
PAINT MONO (-5790 3260);
DISPLAY INVISIBLE (-5790 3260);
FORCEPROP 1 LASTPIN (-5800 3250) BN 2
J 2
(-5788 3258);
DISPLAY 0.489362 (-5788 3258);
PAINT GREEN (-5788 3258);
FORCEPROP 2 LAST CDS_LIB mstr_standard
J 0
(-5850 3250);
DISPLAY 0.723404 (-5850 3250);
PAINT MONO (-5850 3250);
DISPLAY INVISIBLE (-5850 3250);
FORCEPROP 1 LAST BODY_TYPE PLUMBING
J 2
(-5850 3300);
DISPLAY 0.872340 (-5850 3300);
PAINT GREEN (-5850 3300);
DISPLAY INVISIBLE (-5850 3300);
FORCEPROP 1 LAST HDL_TAP TRUE
J 2
(-6175 3125);
DISPLAY 0.872340 (-6175 3125);
DISPLAY INVISIBLE (-6175 3125);
FORCEPROP 1 LAST PATH I296
J 2
(-5848 3250);
DISPLAY 0.872340 (-5848 3250);
PAINT GREEN (-5848 3250);
DISPLAY INVISIBLE (-5848 3250);
FORCEADD TAP..1
R 2
(-5850 3300);
FORCEPROP 3 LASTPIN (-5800 3300) SIG_NAME M_K_CPU1_SB_CA<1>
J 0
(-5790 3310);
DISPLAY 0.659574 (-5790 3310);
PAINT MONO (-5790 3310);
DISPLAY INVISIBLE (-5790 3310);
FORCEPROP 1 LASTPIN (-5800 3300) BN 1
J 2
(-5788 3308);
DISPLAY 0.489362 (-5788 3308);
PAINT GREEN (-5788 3308);
FORCEPROP 2 LAST CDS_LIB mstr_standard
J 0
(-5850 3300);
DISPLAY 0.723404 (-5850 3300);
PAINT MONO (-5850 3300);
DISPLAY INVISIBLE (-5850 3300);
FORCEPROP 1 LAST BODY_TYPE PLUMBING
J 2
(-5850 3350);
DISPLAY 0.872340 (-5850 3350);
PAINT GREEN (-5850 3350);
DISPLAY INVISIBLE (-5850 3350);
FORCEPROP 1 LAST HDL_TAP TRUE
J 2
(-6175 3175);
DISPLAY 0.872340 (-6175 3175);
DISPLAY INVISIBLE (-6175 3175);
FORCEPROP 1 LAST PATH I297
J 2
(-5848 3300);
DISPLAY 0.872340 (-5848 3300);
PAINT GREEN (-5848 3300);
DISPLAY INVISIBLE (-5848 3300);
FORCEADD TAP..1
R 2
(-5850 3200);
FORCEPROP 3 LASTPIN (-5800 3200) SIG_NAME M_K_CPU1_SB_CA<3>
J 0
(-5790 3210);
DISPLAY 0.659574 (-5790 3210);
PAINT MONO (-5790 3210);
DISPLAY INVISIBLE (-5790 3210);
FORCEPROP 1 LASTPIN (-5800 3200) BN 3
J 2
(-5788 3208);
DISPLAY 0.489362 (-5788 3208);
PAINT GREEN (-5788 3208);
FORCEPROP 2 LAST CDS_LIB mstr_standard
J 0
(-5850 3200);
DISPLAY 0.723404 (-5850 3200);
PAINT MONO (-5850 3200);
DISPLAY INVISIBLE (-5850 3200);
FORCEPROP 1 LAST BODY_TYPE PLUMBING
J 2
(-5850 3250);
DISPLAY 0.872340 (-5850 3250);
PAINT GREEN (-5850 3250);
DISPLAY INVISIBLE (-5850 3250);
FORCEPROP 1 LAST HDL_TAP TRUE
J 2
(-6175 3075);
DISPLAY 0.872340 (-6175 3075);
DISPLAY INVISIBLE (-6175 3075);
FORCEPROP 1 LAST PATH I298
J 2
(-5848 3200);
DISPLAY 0.872340 (-5848 3200);
PAINT GREEN (-5848 3200);
DISPLAY INVISIBLE (-5848 3200);
FORCEADD TAP..1
R 2
(-5850 3150);
FORCEPROP 3 LASTPIN (-5800 3150) SIG_NAME M_K_CPU1_SB_CA<4>
J 0
(-5790 3160);
DISPLAY 0.659574 (-5790 3160);
PAINT MONO (-5790 3160);
DISPLAY INVISIBLE (-5790 3160);
FORCEPROP 1 LASTPIN (-5800 3150) BN 4
J 2
(-5788 3158);
DISPLAY 0.489362 (-5788 3158);
PAINT GREEN (-5788 3158);
FORCEPROP 2 LAST CDS_LIB mstr_standard
J 0
(-5850 3150);
DISPLAY 0.723404 (-5850 3150);
PAINT MONO (-5850 3150);
DISPLAY INVISIBLE (-5850 3150);
FORCEPROP 1 LAST BODY_TYPE PLUMBING
J 2
(-5850 3200);
DISPLAY 0.872340 (-5850 3200);
PAINT GREEN (-5850 3200);
DISPLAY INVISIBLE (-5850 3200);
FORCEPROP 1 LAST HDL_TAP TRUE
J 2
(-6175 3025);
DISPLAY 0.872340 (-6175 3025);
DISPLAY INVISIBLE (-6175 3025);
FORCEPROP 1 LAST PATH I299
J 2
(-5848 3150);
DISPLAY 0.872340 (-5848 3150);
PAINT GREEN (-5848 3150);
DISPLAY INVISIBLE (-5848 3150);
FORCEADD TAP..1
R 2
(-5850 3100);
FORCEPROP 3 LASTPIN (-5800 3100) SIG_NAME M_K_CPU1_SB_CA<5>
J 0
(-5790 3110);
DISPLAY 0.659574 (-5790 3110);
PAINT MONO (-5790 3110);
DISPLAY INVISIBLE (-5790 3110);
FORCEPROP 1 LASTPIN (-5800 3100) BN 5
J 2
(-5788 3108);
DISPLAY 0.489362 (-5788 3108);
PAINT GREEN (-5788 3108);
FORCEPROP 2 LAST CDS_LIB mstr_standard
J 0
(-5850 3100);
DISPLAY 0.723404 (-5850 3100);
PAINT MONO (-5850 3100);
DISPLAY INVISIBLE (-5850 3100);
FORCEPROP 1 LAST BODY_TYPE PLUMBING
J 2
(-5850 3150);
DISPLAY 0.872340 (-5850 3150);
PAINT GREEN (-5850 3150);
DISPLAY INVISIBLE (-5850 3150);
FORCEPROP 1 LAST HDL_TAP TRUE
J 2
(-6175 2975);
DISPLAY 0.872340 (-6175 2975);
DISPLAY INVISIBLE (-6175 2975);
FORCEPROP 1 LAST PATH I300
J 2
(-5848 3100);
DISPLAY 0.872340 (-5848 3100);
PAINT GREEN (-5848 3100);
DISPLAY INVISIBLE (-5848 3100);
FORCEADD TAP..1
R 2
(-5850 3050);
FORCEPROP 3 LASTPIN (-5800 3050) SIG_NAME M_K_CPU1_SB_CA<6>
J 0
(-5790 3060);
DISPLAY 0.659574 (-5790 3060);
PAINT MONO (-5790 3060);
DISPLAY INVISIBLE (-5790 3060);
FORCEPROP 1 LASTPIN (-5800 3050) BN 6
J 2
(-5788 3058);
DISPLAY 0.489362 (-5788 3058);
PAINT GREEN (-5788 3058);
FORCEPROP 2 LAST CDS_LIB mstr_standard
J 0
(-5850 3050);
DISPLAY 0.723404 (-5850 3050);
PAINT MONO (-5850 3050);
DISPLAY INVISIBLE (-5850 3050);
FORCEPROP 1 LAST BODY_TYPE PLUMBING
J 2
(-5850 3100);
DISPLAY 0.872340 (-5850 3100);
PAINT GREEN (-5850 3100);
DISPLAY INVISIBLE (-5850 3100);
FORCEPROP 1 LAST HDL_TAP TRUE
J 2
(-6175 2925);
DISPLAY 0.872340 (-6175 2925);
DISPLAY INVISIBLE (-6175 2925);
FORCEPROP 1 LAST PATH I301
J 2
(-5848 3050);
DISPLAY 0.872340 (-5848 3050);
PAINT GREEN (-5848 3050);
DISPLAY INVISIBLE (-5848 3050);
FORCEADD OFFPAGE..2
R 2
(-6450 3775);
FORCEPROP 2 LAST $XR0 107 
J 0
(-6705 3775);
DISPLAY 0.638298 (-6705 3775);
PAINT MONO (-6705 3775);
FORCEPROP 2 LAST PATH I302
J 0
(-6700 3825);
DISPLAY 1.021277 (-6700 3825);
DISPLAY INVISIBLE (-6700 3825);
FORCEPROP 1 LAST COMMENT_BODY TRUE
J 2
(-6405 3680);
DISPLAY 0.872340 (-6405 3680);
PAINT GREEN (-6405 3680);
DISPLAY INVISIBLE (-6405 3680);
FORCEPROP 1 LAST OFFPAGE TRUE
J 2
(-6775 3650);
DISPLAY 0.872340 (-6775 3650);
PAINT GREEN (-6775 3650);
DISPLAY INVISIBLE (-6775 3650);
FORCEPROP 2 LAST CDS_LIB standard
J 0
(-6450 3775);
DISPLAY INVISIBLE (-6450 3775);
FORCEADD OFFPAGE..2
R 2
(-6450 3375);
FORCEPROP 2 LAST $XR0 107 
J 0
(-6705 3375);
DISPLAY 0.638298 (-6705 3375);
PAINT MONO (-6705 3375);
FORCEPROP 2 LAST PATH I303
J 0
(-6700 3425);
DISPLAY 1.021277 (-6700 3425);
DISPLAY INVISIBLE (-6700 3425);
FORCEPROP 1 LAST COMMENT_BODY TRUE
J 2
(-6405 3280);
DISPLAY 0.872340 (-6405 3280);
PAINT GREEN (-6405 3280);
DISPLAY INVISIBLE (-6405 3280);
FORCEPROP 1 LAST OFFPAGE TRUE
J 2
(-6775 3250);
DISPLAY 0.872340 (-6775 3250);
PAINT GREEN (-6775 3250);
DISPLAY INVISIBLE (-6775 3250);
FORCEPROP 2 LAST CDS_LIB standard
J 0
(-6450 3375);
DISPLAY INVISIBLE (-6450 3375);
FORCEADD OFFPAGE..2
R 2
(-6450 2850);
FORCEPROP 2 LAST $XR0 107 
J 0
(-6705 2850);
DISPLAY 0.638298 (-6705 2850);
PAINT MONO (-6705 2850);
FORCEPROP 2 LAST PATH I304
J 0
(-6700 2900);
DISPLAY 1.021277 (-6700 2900);
DISPLAY INVISIBLE (-6700 2900);
FORCEPROP 1 LAST COMMENT_BODY TRUE
J 2
(-6405 2755);
DISPLAY 0.872340 (-6405 2755);
PAINT GREEN (-6405 2755);
DISPLAY INVISIBLE (-6405 2755);
FORCEPROP 1 LAST OFFPAGE TRUE
J 2
(-6775 2725);
DISPLAY 0.872340 (-6775 2725);
PAINT GREEN (-6775 2725);
DISPLAY INVISIBLE (-6775 2725);
FORCEPROP 2 LAST CDS_LIB standard
J 0
(-6450 2850);
DISPLAY INVISIBLE (-6450 2850);
FORCEADD OFFPAGE..2
R 2
(-6450 2900);
FORCEPROP 2 LAST $XR0 107 
J 0
(-6705 2900);
DISPLAY 0.638298 (-6705 2900);
PAINT MONO (-6705 2900);
FORCEPROP 2 LAST PATH I305
J 0
(-6700 2950);
DISPLAY 1.021277 (-6700 2950);
DISPLAY INVISIBLE (-6700 2950);
FORCEPROP 1 LAST COMMENT_BODY TRUE
J 2
(-6405 2805);
DISPLAY 0.872340 (-6405 2805);
PAINT GREEN (-6405 2805);
DISPLAY INVISIBLE (-6405 2805);
FORCEPROP 1 LAST OFFPAGE TRUE
J 2
(-6775 2775);
DISPLAY 0.872340 (-6775 2775);
PAINT GREEN (-6775 2775);
DISPLAY INVISIBLE (-6775 2775);
FORCEPROP 2 LAST CDS_LIB standard
J 0
(-6450 2900);
DISPLAY INVISIBLE (-6450 2900);
FORCEADD OFFPAGE..2
R 2
(-6450 2750);
FORCEPROP 2 LAST $XR0 107 
J 0
(-6705 2750);
DISPLAY 0.638298 (-6705 2750);
PAINT MONO (-6705 2750);
FORCEPROP 2 LAST PATH I306
J 0
(-6700 2800);
DISPLAY 1.021277 (-6700 2800);
DISPLAY INVISIBLE (-6700 2800);
FORCEPROP 1 LAST COMMENT_BODY TRUE
J 2
(-6405 2655);
DISPLAY 0.872340 (-6405 2655);
PAINT GREEN (-6405 2655);
DISPLAY INVISIBLE (-6405 2655);
FORCEPROP 1 LAST OFFPAGE TRUE
J 2
(-6775 2625);
DISPLAY 0.872340 (-6775 2625);
PAINT GREEN (-6775 2625);
DISPLAY INVISIBLE (-6775 2625);
FORCEPROP 2 LAST CDS_LIB standard
J 0
(-6450 2750);
DISPLAY INVISIBLE (-6450 2750);
FORCEADD OFFPAGE..2
R 2
(-6450 2700);
FORCEPROP 2 LAST $XR0 107 
J 0
(-6705 2700);
DISPLAY 0.638298 (-6705 2700);
PAINT MONO (-6705 2700);
FORCEPROP 2 LAST PATH I307
J 0
(-6700 2750);
DISPLAY 1.021277 (-6700 2750);
DISPLAY INVISIBLE (-6700 2750);
FORCEPROP 1 LAST COMMENT_BODY TRUE
J 2
(-6405 2605);
DISPLAY 0.872340 (-6405 2605);
PAINT GREEN (-6405 2605);
DISPLAY INVISIBLE (-6405 2605);
FORCEPROP 1 LAST OFFPAGE TRUE
J 2
(-6775 2575);
DISPLAY 0.872340 (-6775 2575);
PAINT GREEN (-6775 2575);
DISPLAY INVISIBLE (-6775 2575);
FORCEPROP 2 LAST CDS_LIB standard
J 0
(-6450 2700);
DISPLAY INVISIBLE (-6450 2700);
FORCEADD OFFPAGE..1
(-6450 2600);
FORCEPROP 2 LAST $XR0 107 
J 0
(-6732 2600);
DISPLAY 0.638298 (-6732 2600);
PAINT MONO (-6732 2600);
FORCEPROP 2 LAST PATH I308
J 0
(-6725 2650);
DISPLAY 1.021277 (-6725 2650);
DISPLAY INVISIBLE (-6725 2650);
FORCEPROP 1 LAST COMMENT_BODY TRUE
J 0
(-6325 2500);
DISPLAY 0.872340 (-6325 2500);
PAINT GREEN (-6325 2500);
DISPLAY INVISIBLE (-6325 2500);
FORCEPROP 1 LAST OFFPAGE TRUE
J 0
(-6125 2475);
DISPLAY 0.872340 (-6125 2475);
PAINT GREEN (-6125 2475);
DISPLAY INVISIBLE (-6125 2475);
FORCEPROP 2 LAST CDS_LIB standard
J 0
(-6450 2600);
DISPLAY INVISIBLE (-6450 2600);
FORCEADD OFFPAGE..5
(-6450 2500);
FORCEPROP 2 LAST $XR0 107 
J 0
(-6705 2500);
DISPLAY 0.638298 (-6705 2500);
PAINT MONO (-6705 2500);
FORCEPROP 2 LAST PATH I309
J 0
(-6700 2550);
DISPLAY 1.021277 (-6700 2550);
DISPLAY INVISIBLE (-6700 2550);
FORCEPROP 1 LAST COMMENT_BODY TRUE
J 0
(-6350 2425);
DISPLAY 0.872340 (-6350 2425);
PAINT GREEN (-6350 2425);
DISPLAY INVISIBLE (-6350 2425);
FORCEPROP 1 LAST OFFPAGE TRUE
J 0
(-6125 2375);
DISPLAY 0.872340 (-6125 2375);
PAINT GREEN (-6125 2375);
DISPLAY INVISIBLE (-6125 2375);
FORCEPROP 2 LAST CDS_LIB mstr_standard
J 0
(-6450 2500);
DISPLAY INVISIBLE (-6450 2500);
FORCEADD OFFPAGE..2
R 2
(-6450 2400);
FORCEPROP 2 LAST $XR0 107 
J 0
(-6705 2400);
DISPLAY 0.638298 (-6705 2400);
PAINT MONO (-6705 2400);
FORCEPROP 2 LAST PATH I310
J 0
(-6700 2450);
DISPLAY 1.021277 (-6700 2450);
DISPLAY INVISIBLE (-6700 2450);
FORCEPROP 1 LAST COMMENT_BODY TRUE
J 2
(-6405 2305);
DISPLAY 0.872340 (-6405 2305);
PAINT GREEN (-6405 2305);
DISPLAY INVISIBLE (-6405 2305);
FORCEPROP 1 LAST OFFPAGE TRUE
J 2
(-6775 2275);
DISPLAY 0.872340 (-6775 2275);
PAINT GREEN (-6775 2275);
DISPLAY INVISIBLE (-6775 2275);
FORCEPROP 2 LAST CDS_LIB standard
J 0
(-6450 2400);
DISPLAY INVISIBLE (-6450 2400);
FORCEADD OFFPAGE..2
R 2
(-6450 2350);
FORCEPROP 2 LAST $XR0 107 
J 0
(-6705 2350);
DISPLAY 0.638298 (-6705 2350);
PAINT MONO (-6705 2350);
FORCEPROP 2 LAST PATH I311
J 0
(-6700 2400);
DISPLAY 1.021277 (-6700 2400);
DISPLAY INVISIBLE (-6700 2400);
FORCEPROP 1 LAST COMMENT_BODY TRUE
J 2
(-6405 2255);
DISPLAY 0.872340 (-6405 2255);
PAINT GREEN (-6405 2255);
DISPLAY INVISIBLE (-6405 2255);
FORCEPROP 1 LAST OFFPAGE TRUE
J 2
(-6775 2225);
DISPLAY 0.872340 (-6775 2225);
PAINT GREEN (-6775 2225);
DISPLAY INVISIBLE (-6775 2225);
FORCEPROP 2 LAST CDS_LIB standard
J 0
(-6450 2350);
DISPLAY INVISIBLE (-6450 2350);
FORCEADD OFFPAGE..1
(-6450 2250);
FORCEPROP 2 LAST $XR0 107 
J 0
(-6732 2250);
DISPLAY 0.638298 (-6732 2250);
PAINT MONO (-6732 2250);
FORCEPROP 2 LAST PATH I312
J 0
(-6725 2300);
DISPLAY 1.021277 (-6725 2300);
DISPLAY INVISIBLE (-6725 2300);
FORCEPROP 1 LAST COMMENT_BODY TRUE
J 0
(-6325 2150);
DISPLAY 0.872340 (-6325 2150);
PAINT GREEN (-6325 2150);
DISPLAY INVISIBLE (-6325 2150);
FORCEPROP 1 LAST OFFPAGE TRUE
J 0
(-6125 2125);
DISPLAY 0.872340 (-6125 2125);
PAINT GREEN (-6125 2125);
DISPLAY INVISIBLE (-6125 2125);
FORCEPROP 2 LAST CDS_LIB standard
J 0
(-6450 2250);
DISPLAY INVISIBLE (-6450 2250);
FORCEADD OFFPAGE..5
(-6450 2150);
FORCEPROP 2 LAST $XR0 107 
J 0
(-6705 2150);
DISPLAY 0.638298 (-6705 2150);
PAINT MONO (-6705 2150);
FORCEPROP 2 LAST PATH I313
J 0
(-6700 2200);
DISPLAY 1.021277 (-6700 2200);
DISPLAY INVISIBLE (-6700 2200);
FORCEPROP 1 LAST COMMENT_BODY TRUE
J 0
(-6350 2075);
DISPLAY 0.872340 (-6350 2075);
PAINT GREEN (-6350 2075);
DISPLAY INVISIBLE (-6350 2075);
FORCEPROP 1 LAST OFFPAGE TRUE
J 0
(-6125 2025);
DISPLAY 0.872340 (-6125 2025);
PAINT GREEN (-6125 2025);
DISPLAY INVISIBLE (-6125 2025);
FORCEPROP 2 LAST CDS_LIB standard
J 0
(-6450 2150);
DISPLAY INVISIBLE (-6450 2150);
FORCEADD Q_RES..1
(-6525 2050);
FORCEPROP 1 LAST LOCATION R510
J 0
(-6850 2050);
DISPLAY 0.489362 (-6850 2050);
PAINT SKYBLUE (-6850 2050);
FORCEPROP 0 LAST $SEC 1
J 0
(-6700 2100);
DISPLAY 0.680851 (-6700 2100);
PAINT MONO (-6700 2100);
DISPLAY INVISIBLE (-6700 2100);
FORCEPROP 0 LAST CDS_SEC 1
J 0
(-6700 2100);
DISPLAY 1.021277 (-6700 2100);
DISPLAY INVISIBLE (-6700 2100);
FORCEPROP 1 LASTPIN (-6625 2050) $PN 1
J 0
(-6613 2062);
DISPLAY 0.489362 (-6613 2062);
PAINT MONO (-6613 2062);
FORCEPROP 1 LASTPIN (-6425 2050) $PN 2
J 0
(-6463 2062);
DISPLAY 0.489362 (-6463 2062);
PAINT MONO (-6463 2062);
FORCEPROP 1 LAST TOLERANCE 1%
J 0
(-6250 2050);
DISPLAY 0.489362 (-6250 2050);
PAINT SKYBLUE (-6250 2050);
FORCEPROP 1 LAST VALUE 15   
J 2
(-6200 2050);
DISPLAY 0.489362 (-6200 2050);
PAINT SKYBLUE (-6200 2050);
FORCEPROP 1 LAST PART_NUMBER CS01502FB11
J 0
(-6400 2025);
DISPLAY 0.489362 (-6400 2025);
PAINT SKYBLUE (-6400 2025);
FORCEPROP 1 LAST PACK_TYPE 0402LF
J 0
(-6850 2025);
DISPLAY 0.489362 (-6850 2025);
PAINT SKYBLUE (-6850 2025);
FORCEPROP 2 LAST CDS_LIB pure_quanta
J 0
(-6525 2050);
DISPLAY INVISIBLE (-6525 2050);
FORCEPROP 1 LAST PATH I314
J 0
(-6575 2200);
DISPLAY 0.978723 (-6575 2200);
PAINT WHITE (-6575 2200);
DISPLAY INVISIBLE (-6575 2200);
FORCEPROP 1 LAST WATTAGE 1/16W
J 2
(-6300 2175);
DISPLAY 0.638298 (-6300 2175);
PAINT SKYBLUE (-6300 2175);
DISPLAY INVISIBLE (-6300 2175);
FORCEPROP 1 LAST MATERIAL CHIP
J 0
(-6650 2175);
DISPLAY 0.638298 (-6650 2175);
PAINT SKYBLUE (-6650 2175);
DISPLAY INVISIBLE (-6650 2175);
FORCEADD OFFPAGE..5
(-6450 1950);
FORCEPROP 2 LAST $XR0 107 
J 0
(-6705 1950);
DISPLAY 0.638298 (-6705 1950);
PAINT MONO (-6705 1950);
FORCEPROP 2 LAST PATH I315
J 0
(-6700 2000);
DISPLAY 1.021277 (-6700 2000);
DISPLAY INVISIBLE (-6700 2000);
FORCEPROP 1 LAST COMMENT_BODY TRUE
J 0
(-6350 1875);
DISPLAY 0.872340 (-6350 1875);
PAINT GREEN (-6350 1875);
DISPLAY INVISIBLE (-6350 1875);
FORCEPROP 1 LAST OFFPAGE TRUE
J 0
(-6125 1825);
DISPLAY 0.872340 (-6125 1825);
PAINT GREEN (-6125 1825);
DISPLAY INVISIBLE (-6125 1825);
FORCEPROP 2 LAST CDS_LIB standard
J 0
(-6450 1950);
DISPLAY INVISIBLE (-6450 1950);
FORCEADD OFFPAGE..1
(-7400 2050);
FORCEPROP 2 LAST $XR0 107 
J 0
(-7652 2050);
DISPLAY 0.638298 (-7652 2050);
PAINT MONO (-7652 2050);
FORCEPROP 2 LAST PATH I316
J 0
(-7650 2100);
DISPLAY 1.021277 (-7650 2100);
DISPLAY INVISIBLE (-7650 2100);
FORCEPROP 1 LAST COMMENT_BODY TRUE
J 0
(-7275 1950);
DISPLAY 0.872340 (-7275 1950);
PAINT GREEN (-7275 1950);
DISPLAY INVISIBLE (-7275 1950);
FORCEPROP 1 LAST OFFPAGE TRUE
J 0
(-7075 1925);
DISPLAY 0.872340 (-7075 1925);
PAINT GREEN (-7075 1925);
DISPLAY INVISIBLE (-7075 1925);
FORCEPROP 2 LAST CDS_LIB mstr_standard
J 0
(-7400 2050);
DISPLAY INVISIBLE (-7400 2050);
FORCEADD CAD_NOTE..1
(-7575 2350);
FORCEPROP 0 LAST L1 R1956 PLACE CLOSE TO CPU < 25MM
J 0
(-7725 2225);
DISPLAY 0.617021 (-7725 2225);
PAINT WHITE (-7725 2225);
FORCEPROP 2 LAST CDS_LIB pure_quanta_power
J 0
(-7575 2350);
DISPLAY INVISIBLE (-7575 2350);
FORCEPROP 1 LAST COMMENT_BODY TRUE
J 0
(-7550 2450);
DISPLAY 0.574468 (-7550 2450);
PAINT WHITE (-7550 2450);
DISPLAY INVISIBLE (-7550 2450);
FORCEADD QUANTA_TITLE_BLOCK_C..1
(0 0);
FORCEPROP 0 LAST CDS_CON_LAST_MODIFIED Fri Mar 11 14:52:34 2022
J 0
(-1885 15);
DISPLAY INVISIBLE (-1885 15);
FORCEPROP 1 LAST CUSTOM_TXT_CDS <CON_LAST_MODIFIED>
J 0
(-1885 15);
DISPLAY 0.978723 (-1885 15);
FORCEPROP 2 LAST CUSTOM_TXT_CDS <XR_PAGE_TITLE>
J 0
(-7890 5250);
DISPLAY 0.638298 (-7890 5250);
PAINT PINK (-7890 5250);
DISPLAY INVISIBLE (-7890 5250);
FORCEPROP 1 LAST CUSTOM_TXT_CDS <NAME_2>
J 0
(-3175 50);
FORCEPROP 1 LAST CUSTOM_TXT_CDS <NAME_1>
J 0
(-3175 175);
FORCEPROP 1 LAST CUSTOM_TXT_CDS <Q_NUMBER>
J 0
(-1403 103);
DISPLAY 1.212766 (-1403 103);
FORCEPROP 1 LAST CUSTOM_TXT_CDS <Q_PROJ>
J 0
(-2382 102);
DISPLAY 1.212766 (-2382 102);
FORCEPROP 1 LAST CUSTOM_TXT_CDS <Q_REV>
J 0
(-184 103);
DISPLAY 1.212766 (-184 103);
FORCEPROP 1 LAST CUSTOM_TXT_CDS <CON_PAGE_NUM> OF <CON_TOTAL_PAGES>
J 0
(-446 18);
DISPLAY 0.978723 (-446 18);
FORCEPROP 1 LAST Q_TITLE CPU1 DDR CHK
J 0
(-9366 26);
DISPLAY 2.446809 (-9366 26);
PAINT GREEN (-9366 26);
FORCEPROP 1 LAST Q_DEPT BU9
J 1
(-3763 49);
DISPLAY 1.957447 (-3763 49);
PAINT GREEN (-3763 49);
FORCEPROP 2 LAST PAGE_BORDER TRUE
J 0
(-7890 5250);
DISPLAY 0.638298 (-7890 5250);
PAINT PINK (-7890 5250);
DISPLAY INVISIBLE (-7890 5250);
FORCEPROP 1 LAST CDS_LMAN_SYM_OUTLINE -9475,6775,100,-125
J 0
(0 0);
DISPLAY 0.468085 (0 0);
PAINT GREEN (0 0);
DISPLAY INVISIBLE (0 0);
FORCEPROP 2 LAST CDS_LIB pure_quanta
J 0
(0 0);
DISPLAY INVISIBLE (0 0);
FORCEPROP 1 LAST COMMENT_BODY TRUE
J 0
(12 -13);
DISPLAY 0.978723 (12 -13);
PAINT GREEN (12 -13);
DISPLAY INVISIBLE (12 -13);
FORCEPROP 2 LAST CDS_XR_PAGE_TITLE CR-47 : @T6G_MB_LIB.T6G(SCH_1):PAGE47
J 0
(-7890 5250);
DISPLAY 0.638298 (-7890 5250);
PAINT PINK (-7890 5250);
DISPLAY INVISIBLE (-7890 5250);
WIRE 17 -1 (-3175 5375)(-3175 5325);
WIRE 17 -1 (-3175 5425)(-3175 5375);
WIRE 17 -1 (-3175 5325)(-3175 5275);
WIRE 17 -1 (-3175 5275)(-3175 5225);
WIRE 17 -1 (-3175 5475)(-3175 5425);
WIRE 17 -1 (-3175 5575)(-3175 5475);
WIRE 17 -1 (-3175 5225)(-3175 5175);
WIRE 17 -1 (-3175 5175)(-3175 5125);
WIRE 17 -1 (-3175 5625)(-3175 5575);
WIRE 17 -1 (-3175 5675)(-3175 5625);
WIRE 17 -1 (-3175 5025)(-3175 5125);
WIRE 17 -1 (-3175 4975)(-3175 5025);
WIRE 17 -1 (-3175 5725)(-3175 5675);
WIRE 17 -1 (-3175 5775)(-3175 5725);
WIRE 17 -1 (-3175 4925)(-3175 4975);
WIRE 17 -1 (-3175 4875)(-3175 4925);
WIRE 17 -1 (-3175 5825)(-3175 5775);
WIRE 17 -1 (-3175 5875)(-3175 5825);
WIRE 17 -1 (-3175 4875)(-3175 4825);
WIRE 17 -1 (-3175 4825)(-3175 4775);
WIRE 17 -1 (-3175 5925)(-3175 5875);
WIRE 17 -1 (-3175 5925)(-2550 5925);
FORCEPROP 2 LAST SIG_NAME M_K_CPU1_SA_DQ<31:0>
J 2
(-2610 5935);
DISPLAY 0.489362 (-2610 5935);
WIRE 17 -1 (-3175 4775)(-3175 4725);
WIRE 17 -1 (-3175 4725)(-3175 4675);
WIRE 17 -1 (-3175 4675)(-3175 4575);
WIRE 17 -1 (-3175 4575)(-3175 4525);
WIRE 17 -1 (-3175 4525)(-3175 4475);
WIRE 17 -1 (-3175 4475)(-3175 4425);
WIRE 17 -1 (-3175 4375)(-3175 4425);
WIRE 17 -1 (-3175 4325)(-3175 4375);
WIRE 17 -1 (-3175 4275)(-3175 4325);
WIRE 17 -1 (-3175 4225)(-3175 4275);
WIRE 17 -1 (-3175 4125)(-2550 4125);
FORCEPROP 2 LAST SIG_NAME M_K_CPU1_SB_DQ<31:0>
J 2
(-2610 4135);
DISPLAY 0.489362 (-2610 4135);
WIRE 17 -1 (-3175 3575)(-3175 3525);
WIRE 17 -1 (-3175 3625)(-3175 3575);
WIRE 17 -1 (-3175 3525)(-3175 3475);
WIRE 17 -1 (-3175 3475)(-3175 3425);
WIRE 17 -1 (-3175 3675)(-3175 3625);
WIRE 17 -1 (-3175 3775)(-3175 3675);
WIRE 17 -1 (-3175 3425)(-3175 3375);
WIRE 17 -1 (-3175 3375)(-3175 3325);
WIRE 17 -1 (-3175 3825)(-3175 3775);
WIRE 17 -1 (-3175 3875)(-3175 3825);
WIRE 17 -1 (-3175 3225)(-3175 3325);
WIRE 17 -1 (-3175 3175)(-3175 3225);
WIRE 17 -1 (-3175 3925)(-3175 3875);
WIRE 17 -1 (-3175 3975)(-3175 3925);
WIRE 17 -1 (-3175 3125)(-3175 3175);
WIRE 17 -1 (-3175 3075)(-3175 3125);
WIRE 17 -1 (-3175 4025)(-3175 3975);
WIRE 17 -1 (-3175 4075)(-3175 4025);
WIRE 17 -1 (-3175 3075)(-3175 3025);
WIRE 17 -1 (-3175 3025)(-3175 2975);
WIRE 17 -1 (-3175 4125)(-3175 4075);
WIRE 17 -1 (-3175 2975)(-3175 2925);
WIRE 17 -1 (-3175 2925)(-3175 2875);
WIRE 17 -1 (-3175 2875)(-3175 2775);
WIRE 17 -1 (-3175 2775)(-3175 2725);
WIRE 17 -1 (-3175 2725)(-3175 2675);
WIRE 17 -1 (-3175 2675)(-3175 2625);
WIRE 17 -1 (-3175 2575)(-3175 2625);
WIRE 17 -1 (-3175 2525)(-3175 2575);
WIRE 17 -1 (-3175 2475)(-3175 2525);
WIRE 17 -1 (-3175 2425)(-3175 2475);
WIRE 17 -1 (-3175 2325)(-3175 2275);
WIRE 17 -1 (-3175 2325)(-3175 2350);
WIRE 17 -1 (-3175 2225)(-3175 2275);
WIRE 17 -1 (-3175 2225)(-3175 2175);
WIRE 17 -1 (-3175 2350)(-2675 2350);
FORCEPROP 2 LAST SIG_NAME M_K_CPU1_SA_CB<7:0>
J 2
(-2675 2360);
DISPLAY 0.489362 (-2675 2360);
WIRE 17 -1 (-3175 2125)(-3175 2175);
WIRE 17 -1 (-3175 2075)(-3175 2125);
WIRE 17 -1 (-3175 2025)(-3175 2075);
WIRE 17 -1 (-3175 1975)(-3175 2025);
WIRE 17 -1 (-3175 1875)(-3175 1900);
WIRE 17 -1 (-3175 1875)(-3175 1825);
WIRE 17 -1 (-3175 1900)(-2675 1900);
FORCEPROP 2 LAST SIG_NAME M_K_CPU1_SB_CB<7:0>
J 2
(-2675 1910);
DISPLAY 0.489362 (-2675 1910);
WIRE 17 -1 (-3175 1775)(-3175 1825);
WIRE 17 -1 (-3175 1775)(-3175 1725);
WIRE 17 -1 (-3175 1675)(-3175 1725);
WIRE 17 -1 (-3175 1625)(-3175 1675);
WIRE 17 -1 (-3175 1575)(-3175 1625);
WIRE 17 -1 (-3175 1525)(-3175 1575);
WIRE 17 -1 (-5700 5925)(-5700 5825);
WIRE 17 -1 (-5700 5925)(-6500 5925);
FORCEPROP 2 LAST SIG_NAME M_K_CPU1_SA_DQS_DP<9:0>
J 2
(-5935 5935);
DISPLAY 0.489362 (-5935 5935);
WIRE 17 -1 (-5700 5825)(-5700 5725);
WIRE 17 -1 (-5700 5725)(-5700 5625);
WIRE 17 -1 (-5700 5625)(-5700 5525);
WIRE 17 -1 (-5700 5425)(-5700 5525);
WIRE 17 -1 (-5700 5325)(-5700 5425);
WIRE 17 -1 (-5700 5225)(-5700 5325);
WIRE 17 -1 (-5700 5225)(-5700 5125);
WIRE 17 -1 (-5700 5125)(-5700 5025);
WIRE 17 -1 (-5900 5875)(-5900 5775);
FORCEPROP 2 LAST SIG_NAME M_K_CPU1_SA_DQS_DN<9:0>
J 2
(-5935 5885);
DISPLAY 0.489362 (-5935 5885);
WIRE 17 -1 (-5900 5675)(-5900 5575);
WIRE 17 -1 (-5900 5775)(-5900 5675);
WIRE 17 -1 (-5900 5575)(-5900 5475);
WIRE 17 -1 (-5900 5375)(-5900 5475);
WIRE 17 -1 (-5900 5275)(-5900 5375);
WIRE 17 -1 (-5900 5175)(-5900 5275);
WIRE 17 -1 (-5900 5175)(-5900 5075);
WIRE 17 -1 (-5900 5075)(-5900 4975);
WIRE 17 -1 (-5700 4675)(-5700 4575);
WIRE 17 -1 (-5700 4775)(-5700 4675);
WIRE 17 -1 (-5700 4575)(-5700 4475);
WIRE 17 -1 (-5700 4375)(-5700 4475);
WIRE 17 -1 (-5700 4875)(-5700 4775);
WIRE 17 -1 (-5700 4875)(-6500 4875);
FORCEPROP 2 LAST SIG_NAME M_K_CPU1_SB_DQS_DP<9:0>
J 2
(-5935 4885);
DISPLAY 0.489362 (-5935 4885);
WIRE 17 -1 (-5700 4275)(-5700 4375);
WIRE 17 -1 (-5700 4175)(-5700 4275);
WIRE 17 -1 (-5700 4175)(-5700 4075);
WIRE 17 -1 (-5700 4075)(-5700 3975);
WIRE 17 -1 (-5900 4225)(-5900 4325);
WIRE 17 -1 (-5900 4125)(-5900 4225);
WIRE 17 -1 (-5900 4325)(-5900 4425);
WIRE 17 -1 (-5900 4525)(-5900 4425);
WIRE 17 -1 (-5900 4125)(-5900 4025);
WIRE 17 -1 (-5900 4025)(-5900 3925);
WIRE 17 -1 (-5900 4625)(-5900 4525);
WIRE 17 -1 (-5900 4725)(-5900 4625);
WIRE 17 -1 (-5900 4825)(-5900 4725);
FORCEPROP 2 LAST SIG_NAME M_K_CPU1_SB_DQS_DN<9:0>
J 2
(-5935 4835);
DISPLAY 0.489362 (-5935 4835);
WIRE 17 -1 (-5900 3325)(-5900 3375);
WIRE 17 -1 (-5900 3275)(-5900 3325);
WIRE 17 -1 (-5900 3375)(-6400 3375);
FORCEPROP 2 LAST SIG_NAME M_K_CPU1_SB_CA<6:0>
J 0
(-6400 3385);
DISPLAY 0.489362 (-6400 3385);
WIRE 17 -1 (-5900 3675)(-5900 3725);
WIRE 17 -1 (-5900 3625)(-5900 3675);
WIRE 17 -1 (-5900 3725)(-5900 3775);
WIRE 17 -1 (-5900 3775)(-6400 3775);
FORCEPROP 2 LAST SIG_NAME M_K_CPU1_SA_CA<6:0>
J 0
(-6400 3785);
DISPLAY 0.489362 (-6400 3785);
WIRE 17 -1 (-5900 3225)(-5900 3275);
WIRE 17 -1 (-5900 3575)(-5900 3625);
WIRE 17 -1 (-5900 3525)(-5900 3575);
WIRE 17 -1 (-5900 3475)(-5900 3525);
WIRE 17 -1 (-5900 3175)(-5900 3225);
WIRE 17 -1 (-5900 3125)(-5900 3175);
WIRE 17 -1 (-5900 3075)(-5900 3125);
WIRE 17 -1 (-5900 5875)(-6500 5875);
WIRE 17 -1 (-5900 4825)(-6500 4825);
WIRE 16 -1 (-7350 2050)(-6625 2050);
FORCEPROP 2 LAST SIG_NAME M_K_CPU1_ALERT_N
J 0
(-7310 2060);
DISPLAY 0.489362 (-7310 2060);
WIRE 16 -1 (-6400 1100)(-5300 1100);
FORCEPROP 2 LAST SIG_NAME TP_M_K_CPU1_SA_TEST39K
J 0
(-6385 1110);
DISPLAY 0.489362 (-6385 1110);
FORCEPROP 2 LASTPROP $XRERR UNIQUE?
J 0
(-6640 1100);
DISPLAY 0.638298 (-6640 1100);
PAINT MONO (-6640 1100);
DISPLAY INVISIBLE (-6640 1100);
WIRE 16 -1 (-6425 2050)(-5300 2050);
FORCEPROP 2 LAST SIG_NAME M_K_CPU1_ALERT_R_N
J 0
(-6135 2060);
DISPLAY 0.489362 (-6135 2060);
FORCEPROP 2 LASTPROP $XRERR UNIQUE?
J 0
(-6375 2060);
DISPLAY 0.638298 (-6375 2060);
PAINT MONO (-6375 2060);
DISPLAY INVISIBLE (-6375 2060);
WIRE 16 -1 (-6400 2850)(-5300 2850);
FORCEPROP 2 LAST SIG_NAME M_K_CPU1_CLK_DN<0>
J 0
(-6400 2860);
DISPLAY 0.489362 (-6400 2860);
WIRE 16 -1 (-6400 2900)(-5300 2900);
FORCEPROP 2 LAST SIG_NAME M_K_CPU1_CLK_DP<0>
J 0
(-6400 2910);
DISPLAY 0.489362 (-6400 2910);
WIRE 16 -1 (-6400 2750)(-5300 2750);
FORCEPROP 2 LAST SIG_NAME M_K_CPU1_SA_CS_N<0>
J 0
(-6400 2760);
DISPLAY 0.489362 (-6400 2760);
WIRE 16 -1 (-6400 2700)(-5300 2700);
FORCEPROP 2 LAST SIG_NAME M_K_CPU1_SA_CS_N<1>
J 0
(-6400 2710);
DISPLAY 0.489362 (-6400 2710);
WIRE 16 -1 (-6400 2600)(-5300 2600);
FORCEPROP 2 LAST SIG_NAME M_K_CPU1_SA_RSP<0>
J 0
(-6400 2610);
DISPLAY 0.489362 (-6400 2610);
WIRE 16 -1 (-6400 2500)(-5300 2500);
FORCEPROP 2 LAST SIG_NAME M_K_CPU1_SA_PAR
J 0
(-6400 2510);
DISPLAY 0.489362 (-6400 2510);
WIRE 16 -1 (-6400 2400)(-5300 2400);
FORCEPROP 2 LAST SIG_NAME M_K_CPU1_SB_CS_N<0>
J 0
(-6400 2410);
DISPLAY 0.489362 (-6400 2410);
WIRE 16 -1 (-6400 2350)(-5300 2350);
FORCEPROP 2 LAST SIG_NAME M_K_CPU1_SB_CS_N<1>
J 0
(-6400 2360);
DISPLAY 0.489362 (-6400 2360);
WIRE 16 -1 (-6400 2250)(-5300 2250);
FORCEPROP 2 LAST SIG_NAME M_K_CPU1_SB_RSP<0>
J 0
(-6400 2260);
DISPLAY 0.489362 (-6400 2260);
WIRE 16 -1 (-6400 2150)(-5300 2150);
FORCEPROP 2 LAST SIG_NAME M_K_CPU1_SB_PAR
J 0
(-6400 2160);
DISPLAY 0.489362 (-6400 2160);
WIRE 16 -1 (-6400 1950)(-5300 1950);
FORCEPROP 2 LAST SIG_NAME M_K_CPU1_RESET_N
J 0
(-6400 1960);
DISPLAY 0.489362 (-6400 1960);
WIRE 16 -1 (-5800 3050)(-5300 3050);
WIRE 16 -1 (-5800 3750)(-5300 3750);
WIRE 16 -1 (-5800 3450)(-5300 3450);
WIRE 16 -1 (-5800 3100)(-5300 3100);
WIRE 16 -1 (-5800 3500)(-5300 3500);
WIRE 16 -1 (-5800 3150)(-5300 3150);
WIRE 16 -1 (-5800 3550)(-5300 3550);
WIRE 16 -1 (-5800 3200)(-5300 3200);
WIRE 16 -1 (-5800 3900)(-5300 3900);
WIRE 16 -1 (-5800 3600)(-5300 3600);
WIRE 16 -1 (-5800 3250)(-5300 3250);
WIRE 16 -1 (-5800 4000)(-5300 4000);
WIRE 16 -1 (-5800 3650)(-5300 3650);
WIRE 16 -1 (-5800 3300)(-5300 3300);
WIRE 16 -1 (-5800 3700)(-5300 3700);
WIRE 16 -1 (-5800 3350)(-5300 3350);
WIRE 16 -1 (-5600 3950)(-5300 3950);
WIRE 16 -1 (-5600 4050)(-5300 4050);
WIRE 16 -1 (-5800 4300)(-5300 4300);
WIRE 16 -1 (-5800 4400)(-5300 4400);
WIRE 16 -1 (-5800 4950)(-5300 4950);
WIRE 16 -1 (-5800 4500)(-5300 4500);
WIRE 16 -1 (-5800 5050)(-5300 5050);
WIRE 16 -1 (-5800 4600)(-5300 4600);
WIRE 16 -1 (-5800 4700)(-5300 4700);
WIRE 16 -1 (-5800 4800)(-5300 4800);
WIRE 16 -1 (-5800 4100)(-5300 4100);
WIRE 16 -1 (-5800 4200)(-5300 4200);
WIRE 16 -1 (-5600 4150)(-5300 4150);
WIRE 16 -1 (-5600 4250)(-5300 4250);
WIRE 16 -1 (-5600 4350)(-5300 4350);
WIRE 16 -1 (-5600 4450)(-5300 4450);
WIRE 16 -1 (-5600 4550)(-5300 4550);
WIRE 16 -1 (-5600 4750)(-5300 4750);
WIRE 16 -1 (-5600 4850)(-5300 4850);
WIRE 16 -1 (-5600 5000)(-5300 5000);
WIRE 16 -1 (-5600 5100)(-5300 5100);
WIRE 16 -1 (-5600 4650)(-5300 4650);
WIRE 16 -1 (-5800 5150)(-5300 5150);
WIRE 16 -1 (-5800 5250)(-5300 5250);
WIRE 16 -1 (-5800 5350)(-5300 5350);
WIRE 16 -1 (-5800 5450)(-5300 5450);
WIRE 16 -1 (-5800 5550)(-5300 5550);
WIRE 16 -1 (-5800 5650)(-5300 5650);
WIRE 16 -1 (-5800 5750)(-5300 5750);
WIRE 16 -1 (-5800 5850)(-5300 5850);
WIRE 16 -1 (-5600 5200)(-5300 5200);
WIRE 16 -1 (-5600 5300)(-5300 5300);
WIRE 16 -1 (-5600 5400)(-5300 5400);
WIRE 16 -1 (-5600 5500)(-5300 5500);
WIRE 16 -1 (-5600 5600)(-5300 5600);
WIRE 16 -1 (-5600 5700)(-5300 5700);
WIRE 16 -1 (-5600 5800)(-5300 5800);
WIRE 16 -1 (-5600 5900)(-5300 5900);
WIRE 16 -1 (-3700 1500)(-3275 1500);
WIRE 16 -1 (-3700 1550)(-3275 1550);
WIRE 16 -1 (-3700 1600)(-3275 1600);
WIRE 16 -1 (-3700 1650)(-3275 1650);
WIRE 16 -1 (-3700 1700)(-3275 1700);
WIRE 16 -1 (-3700 1750)(-3275 1750);
WIRE 16 -1 (-3700 1950)(-3275 1950);
WIRE 16 -1 (-3700 1800)(-3275 1800);
WIRE 16 -1 (-3700 2000)(-3275 2000);
WIRE 16 -1 (-3700 1850)(-3275 1850);
WIRE 16 -1 (-3700 2500)(-3275 2500);
WIRE 16 -1 (-3700 2550)(-3275 2550);
WIRE 16 -1 (-3700 2600)(-3275 2600);
WIRE 16 -1 (-3700 2650)(-3275 2650);
WIRE 16 -1 (-3700 2700)(-3275 2700);
WIRE 16 -1 (-3700 2750)(-3275 2750);
WIRE 16 -1 (-3700 2850)(-3275 2850);
WIRE 16 -1 (-3700 2900)(-3275 2900);
WIRE 16 -1 (-3700 2950)(-3275 2950);
WIRE 16 -1 (-3700 3000)(-3275 3000);
WIRE 16 -1 (-3700 2400)(-3275 2400);
WIRE 16 -1 (-3700 2050)(-3275 2050);
WIRE 16 -1 (-3700 2450)(-3275 2450);
WIRE 16 -1 (-3700 2100)(-3275 2100);
WIRE 16 -1 (-3700 2150)(-3275 2150);
WIRE 16 -1 (-3700 2200)(-3275 2200);
WIRE 16 -1 (-3700 2250)(-3275 2250);
WIRE 16 -1 (-3700 2300)(-3275 2300);
WIRE 16 -1 (-3700 3050)(-3275 3050);
WIRE 16 -1 (-3700 3600)(-3275 3600);
WIRE 16 -1 (-3700 3100)(-3275 3100);
WIRE 16 -1 (-3700 3650)(-3275 3650);
WIRE 16 -1 (-3700 3150)(-3275 3150);
WIRE 16 -1 (-3700 3750)(-3275 3750);
WIRE 16 -1 (-3700 3200)(-3275 3200);
WIRE 16 -1 (-3700 3800)(-3275 3800);
WIRE 16 -1 (-3700 3300)(-3275 3300);
WIRE 16 -1 (-3700 3850)(-3275 3850);
WIRE 16 -1 (-3700 3350)(-3275 3350);
WIRE 16 -1 (-3700 3900)(-3275 3900);
WIRE 16 -1 (-3700 3400)(-3275 3400);
WIRE 16 -1 (-3700 3950)(-3275 3950);
WIRE 16 -1 (-3700 3450)(-3275 3450);
WIRE 16 -1 (-3700 4000)(-3275 4000);
WIRE 16 -1 (-3700 3500)(-3275 3500);
WIRE 16 -1 (-3700 4050)(-3275 4050);
WIRE 16 -1 (-3700 3550)(-3275 3550);
WIRE 16 -1 (-3700 4850)(-3275 4850);
WIRE 16 -1 (-3700 4900)(-3275 4900);
WIRE 16 -1 (-3700 4300)(-3275 4300);
WIRE 16 -1 (-3700 4950)(-3275 4950);
WIRE 16 -1 (-3700 4350)(-3275 4350);
WIRE 16 -1 (-3700 5000)(-3275 5000);
WIRE 16 -1 (-3700 4400)(-3275 4400);
WIRE 16 -1 (-3700 5100)(-3275 5100);
WIRE 16 -1 (-3700 4450)(-3275 4450);
WIRE 16 -1 (-3700 4100)(-3275 4100);
WIRE 16 -1 (-3700 4500)(-3275 4500);
WIRE 16 -1 (-3700 4550)(-3275 4550);
WIRE 16 -1 (-3700 4650)(-3275 4650);
WIRE 16 -1 (-3700 4700)(-3275 4700);
WIRE 16 -1 (-3700 4750)(-3275 4750);
WIRE 16 -1 (-3700 4800)(-3275 4800);
WIRE 16 -1 (-3700 4200)(-3275 4200);
WIRE 16 -1 (-3700 4250)(-3275 4250);
WIRE 16 -1 (-3700 5400)(-3275 5400);
WIRE 16 -1 (-3700 5450)(-3275 5450);
WIRE 16 -1 (-3700 5550)(-3275 5550);
WIRE 16 -1 (-3700 5600)(-3275 5600);
WIRE 16 -1 (-3700 5650)(-3275 5650);
WIRE 16 -1 (-3700 5700)(-3275 5700);
WIRE 16 -1 (-3700 5750)(-3275 5750);
WIRE 16 -1 (-3700 5800)(-3275 5800);
WIRE 16 -1 (-3700 5850)(-3275 5850);
WIRE 16 -1 (-3700 5900)(-3275 5900);
WIRE 16 -1 (-3700 5150)(-3275 5150);
WIRE 16 -1 (-3700 5200)(-3275 5200);
WIRE 16 -1 (-3700 5250)(-3275 5250);
WIRE 16 -1 (-3700 5300)(-3275 5300);
WIRE 16 -1 (-3700 5350)(-3275 5350);
QUIT
